FILE_TYPE = MACRO_DRAWING;
SET COLOR_WIRE YELLOW;
SET COLOR_PROP ORANGE;
SET COLOR_DOT WHITE;
SET COLOR_ARC YELLOW;
SET COLOR_BODY GREEN;
SET COLOR_NOTE PURPLE;
SET PROP_DISPLAY VALUE;
SET PAGE_NUMBER P82;
FORCEADD OFFPAGE..5
(-8225 3775);
FORCEPROP 2 LAST $XR3 248 
J 0
(-8809 3775);
DISPLAY 0.638298 (-8809 3775);
PAINT MONO (-8809 3775);
FORCEPROP 2 LAST $XR2 141 
J 0
(-8689 3775);
DISPLAY 0.638298 (-8689 3775);
PAINT MONO (-8689 3775);
FORCEPROP 2 LAST $XR1 140 
J 0
(-8569 3775);
DISPLAY 0.638298 (-8569 3775);
PAINT MONO (-8569 3775);
FORCEPROP 2 LAST $XR0 81 
J 0
(-8449 3775);
DISPLAY 0.638298 (-8449 3775);
PAINT MONO (-8449 3775);
FORCEPROP 2 LAST CDS_LIB standard
J 0
(-8225 3775);
DISPLAY INVISIBLE (-8225 3775);
FORCEPROP 1 LAST OFFPAGE TRUE
J 0
(-7900 3650);
DISPLAY 0.872340 (-7900 3650);
PAINT GREEN (-7900 3650);
DISPLAY INVISIBLE (-7900 3650);
FORCEPROP 1 LAST COMMENT_BODY TRUE
J 0
(-8125 3700);
DISPLAY 0.872340 (-8125 3700);
PAINT GREEN (-8125 3700);
DISPLAY INVISIBLE (-8125 3700);
FORCEPROP 2 LAST PATH I10
J 0
(-8475 3825);
DISPLAY 0.680851 (-8475 3825);
DISPLAY INVISIBLE (-8475 3825);
FORCEADD OFFPAGE..1
R 2
(-2225 3625);
FORCEPROP 2 LAST $XR1 159 
J 0
(-1949 3625);
DISPLAY 0.638298 (-1949 3625);
PAINT MONO (-1949 3625);
FORCEPROP 2 LAST $XR0 80 
J 0
(-2039 3625);
DISPLAY 0.638298 (-2039 3625);
PAINT MONO (-2039 3625);
FORCEPROP 2 LAST CDS_LIB standard
J 0
(-2225 3625);
DISPLAY INVISIBLE (-2225 3625);
FORCEPROP 1 LAST OFFPAGE TRUE
J 2
(-2550 3500);
DISPLAY 0.872340 (-2550 3500);
PAINT GREEN (-2550 3500);
DISPLAY INVISIBLE (-2550 3500);
FORCEPROP 1 LAST COMMENT_BODY TRUE
J 2
(-2350 3525);
DISPLAY 0.872340 (-2350 3525);
PAINT GREEN (-2350 3525);
DISPLAY INVISIBLE (-2350 3525);
FORCEPROP 2 LAST PATH I100
J 0
(-1925 3675);
DISPLAY 0.680851 (-1925 3675);
DISPLAY INVISIBLE (-1925 3675);
FORCEADD OFFPAGE..1
R 2
(-2225 3675);
FORCEPROP 2 LAST $XR1 159 
J 0
(-1949 3675);
DISPLAY 0.638298 (-1949 3675);
PAINT MONO (-1949 3675);
FORCEPROP 2 LAST $XR0 80 
J 0
(-2039 3675);
DISPLAY 0.638298 (-2039 3675);
PAINT MONO (-2039 3675);
FORCEPROP 2 LAST CDS_LIB standard
J 0
(-2225 3675);
DISPLAY INVISIBLE (-2225 3675);
FORCEPROP 1 LAST OFFPAGE TRUE
J 2
(-2550 3550);
DISPLAY 0.872340 (-2550 3550);
PAINT GREEN (-2550 3550);
DISPLAY INVISIBLE (-2550 3550);
FORCEPROP 1 LAST COMMENT_BODY TRUE
J 2
(-2350 3575);
DISPLAY 0.872340 (-2350 3575);
PAINT GREEN (-2350 3575);
DISPLAY INVISIBLE (-2350 3575);
FORCEPROP 2 LAST PATH I101
J 0
(-1925 3725);
DISPLAY 0.680851 (-1925 3725);
DISPLAY INVISIBLE (-1925 3725);
FORCEADD Q_CAP..2
(-1200 525);
FORCEPROP 1 LAST LOCATION C362
J 0
(-1500 525);
DISPLAY 0.489362 (-1500 525);
PAINT SKYBLUE (-1500 525);
FORCEPROP 2 LAST $SEC 1
J 0
(-1200 775);
DISPLAY 0.680851 (-1200 775);
PAINT MONO (-1200 775);
DISPLAY INVISIBLE (-1200 775);
FORCEPROP 2 LAST CDS_SEC 1
J 0
(-1200 775);
DISPLAY 1.021277 (-1200 775);
DISPLAY INVISIBLE (-1200 775);
FORCEPROP 1 LASTPIN (-1300 525) $PN 1
J 0
(-1310 540);
DISPLAY 0.489362 (-1310 540);
PAINT MONO (-1310 540);
FORCEPROP 1 LASTPIN (-1100 525) $PN 2
J 0
(-1115 540);
DISPLAY 0.489362 (-1115 540);
PAINT MONO (-1115 540);
FORCEPROP 1 LAST VALUE 0.1UF
J 2
(-825 525);
DISPLAY 0.489362 (-825 525);
PAINT SKYBLUE (-825 525);
FORCEPROP 1 LAST PACK_TYPE C0402
J 1
(-350 475);
DISPLAY 0.978723 (-350 475);
PAINT SKYBLUE (-350 475);
DISPLAY INVISIBLE (-350 475);
FORCEPROP 1 LAST VOLTAGE 16V
J 0
(-675 475);
DISPLAY 0.978723 (-675 475);
PAINT SKYBLUE (-675 475);
DISPLAY INVISIBLE (-675 475);
FORCEPROP 1 LAST TOLERANCE 10%
J 2
(-925 475);
DISPLAY 0.978723 (-925 475);
PAINT SKYBLUE (-925 475);
DISPLAY INVISIBLE (-925 475);
FORCEPROP 1 LAST MATERIAL X7R
J 0
(-850 475);
DISPLAY 0.978723 (-850 475);
PAINT SKYBLUE (-850 475);
DISPLAY INVISIBLE (-850 475);
FORCEPROP 2 LAST CDS_LIB pure_quanta
J 0
(-1200 525);
DISPLAY INVISIBLE (-1200 525);
FORCEPROP 1 LAST PATH I102
J 0
(-1200 725);
DISPLAY 0.978723 (-1200 725);
PAINT WHITE (-1200 725);
DISPLAY INVISIBLE (-1200 725);
FORCEPROP 1 LAST PART_NUMBER CH4103K1B08
J 1
(-450 525);
DISPLAY 0.978723 (-450 525);
PAINT SKYBLUE (-450 525);
DISPLAY INVISIBLE (-450 525);
FORCEADD Q_CAP..2
(-1200 725);
FORCEPROP 1 LAST LOCATION C360
J 0
(-1500 725);
DISPLAY 0.489362 (-1500 725);
PAINT SKYBLUE (-1500 725);
FORCEPROP 2 LAST $SEC 1
J 0
(-1200 975);
DISPLAY 0.680851 (-1200 975);
PAINT MONO (-1200 975);
DISPLAY INVISIBLE (-1200 975);
FORCEPROP 2 LAST CDS_SEC 1
J 0
(-1200 975);
DISPLAY 1.021277 (-1200 975);
DISPLAY INVISIBLE (-1200 975);
FORCEPROP 1 LASTPIN (-1300 725) $PN 1
J 0
(-1310 740);
DISPLAY 0.489362 (-1310 740);
PAINT MONO (-1310 740);
FORCEPROP 1 LASTPIN (-1100 725) $PN 2
J 0
(-1115 740);
DISPLAY 0.489362 (-1115 740);
PAINT MONO (-1115 740);
FORCEPROP 1 LAST VALUE 0.1UF
J 2
(-825 725);
DISPLAY 0.489362 (-825 725);
PAINT SKYBLUE (-825 725);
FORCEPROP 1 LAST PACK_TYPE C0402
J 1
(-350 675);
DISPLAY 0.978723 (-350 675);
PAINT SKYBLUE (-350 675);
DISPLAY INVISIBLE (-350 675);
FORCEPROP 1 LAST VOLTAGE 16V
J 0
(-675 675);
DISPLAY 0.978723 (-675 675);
PAINT SKYBLUE (-675 675);
DISPLAY INVISIBLE (-675 675);
FORCEPROP 1 LAST TOLERANCE 10%
J 2
(-925 675);
DISPLAY 0.978723 (-925 675);
PAINT SKYBLUE (-925 675);
DISPLAY INVISIBLE (-925 675);
FORCEPROP 1 LAST MATERIAL X7R
J 0
(-850 675);
DISPLAY 0.978723 (-850 675);
PAINT SKYBLUE (-850 675);
DISPLAY INVISIBLE (-850 675);
FORCEPROP 2 LAST CDS_LIB pure_quanta
J 0
(-1200 725);
DISPLAY INVISIBLE (-1200 725);
FORCEPROP 1 LAST PATH I103
J 0
(-1200 925);
DISPLAY 0.978723 (-1200 925);
PAINT WHITE (-1200 925);
DISPLAY INVISIBLE (-1200 925);
FORCEPROP 1 LAST PART_NUMBER CH4103K1B08
J 1
(-450 725);
DISPLAY 0.978723 (-450 725);
PAINT SKYBLUE (-450 725);
DISPLAY INVISIBLE (-450 725);
FORCEADD Q_CAP..2
(-1200 625);
FORCEPROP 1 LAST LOCATION C361
J 0
(-1500 625);
DISPLAY 0.489362 (-1500 625);
PAINT SKYBLUE (-1500 625);
FORCEPROP 2 LAST $SEC 1
J 0
(-1200 875);
DISPLAY 0.680851 (-1200 875);
PAINT MONO (-1200 875);
DISPLAY INVISIBLE (-1200 875);
FORCEPROP 2 LAST CDS_SEC 1
J 0
(-1200 875);
DISPLAY 1.021277 (-1200 875);
DISPLAY INVISIBLE (-1200 875);
FORCEPROP 1 LASTPIN (-1300 625) $PN 1
J 0
(-1310 640);
DISPLAY 0.489362 (-1310 640);
PAINT MONO (-1310 640);
FORCEPROP 1 LASTPIN (-1100 625) $PN 2
J 0
(-1115 640);
DISPLAY 0.489362 (-1115 640);
PAINT MONO (-1115 640);
FORCEPROP 1 LAST VALUE 0.1UF
J 2
(-825 625);
DISPLAY 0.489362 (-825 625);
PAINT SKYBLUE (-825 625);
FORCEPROP 1 LAST PACK_TYPE C0402
J 1
(-350 575);
DISPLAY 0.978723 (-350 575);
PAINT SKYBLUE (-350 575);
DISPLAY INVISIBLE (-350 575);
FORCEPROP 1 LAST VOLTAGE 16V
J 0
(-675 575);
DISPLAY 0.978723 (-675 575);
PAINT SKYBLUE (-675 575);
DISPLAY INVISIBLE (-675 575);
FORCEPROP 1 LAST TOLERANCE 10%
J 2
(-925 575);
DISPLAY 0.978723 (-925 575);
PAINT SKYBLUE (-925 575);
DISPLAY INVISIBLE (-925 575);
FORCEPROP 1 LAST MATERIAL X7R
J 0
(-850 575);
DISPLAY 0.978723 (-850 575);
PAINT SKYBLUE (-850 575);
DISPLAY INVISIBLE (-850 575);
FORCEPROP 2 LAST CDS_LIB pure_quanta
J 0
(-1200 625);
DISPLAY INVISIBLE (-1200 625);
FORCEPROP 1 LAST PATH I104
J 0
(-1200 825);
DISPLAY 0.978723 (-1200 825);
PAINT WHITE (-1200 825);
DISPLAY INVISIBLE (-1200 825);
FORCEPROP 1 LAST PART_NUMBER CH4103K1B08
J 1
(-450 625);
DISPLAY 0.978723 (-450 625);
PAINT SKYBLUE (-450 625);
DISPLAY INVISIBLE (-450 625);
FORCEADD Q_CAP..2
(-1200 925);
FORCEPROP 1 LAST LOCATION C358
J 0
(-1500 925);
DISPLAY 0.489362 (-1500 925);
PAINT SKYBLUE (-1500 925);
FORCEPROP 2 LAST $SEC 1
J 0
(-1200 1175);
DISPLAY 0.680851 (-1200 1175);
PAINT MONO (-1200 1175);
DISPLAY INVISIBLE (-1200 1175);
FORCEPROP 2 LAST CDS_SEC 1
J 0
(-1200 1175);
DISPLAY 1.021277 (-1200 1175);
DISPLAY INVISIBLE (-1200 1175);
FORCEPROP 1 LASTPIN (-1300 925) $PN 1
J 0
(-1310 940);
DISPLAY 0.489362 (-1310 940);
PAINT MONO (-1310 940);
FORCEPROP 1 LASTPIN (-1100 925) $PN 2
J 0
(-1115 940);
DISPLAY 0.489362 (-1115 940);
PAINT MONO (-1115 940);
FORCEPROP 1 LAST VALUE 0.1UF
J 2
(-825 925);
DISPLAY 0.489362 (-825 925);
PAINT SKYBLUE (-825 925);
FORCEPROP 1 LAST PACK_TYPE C0402
J 1
(-350 875);
DISPLAY 0.978723 (-350 875);
PAINT SKYBLUE (-350 875);
DISPLAY INVISIBLE (-350 875);
FORCEPROP 1 LAST VOLTAGE 16V
J 0
(-675 875);
DISPLAY 0.978723 (-675 875);
PAINT SKYBLUE (-675 875);
DISPLAY INVISIBLE (-675 875);
FORCEPROP 1 LAST TOLERANCE 10%
J 2
(-925 875);
DISPLAY 0.978723 (-925 875);
PAINT SKYBLUE (-925 875);
DISPLAY INVISIBLE (-925 875);
FORCEPROP 1 LAST MATERIAL X7R
J 0
(-850 875);
DISPLAY 0.978723 (-850 875);
PAINT SKYBLUE (-850 875);
DISPLAY INVISIBLE (-850 875);
FORCEPROP 2 LAST CDS_LIB pure_quanta
J 0
(-1200 925);
DISPLAY INVISIBLE (-1200 925);
FORCEPROP 1 LAST PATH I105
J 0
(-1200 1125);
DISPLAY 0.978723 (-1200 1125);
PAINT WHITE (-1200 1125);
DISPLAY INVISIBLE (-1200 1125);
FORCEPROP 1 LAST PART_NUMBER CH4103K1B08
J 1
(-450 925);
DISPLAY 0.978723 (-450 925);
PAINT SKYBLUE (-450 925);
DISPLAY INVISIBLE (-450 925);
FORCEADD Q_CAP..2
(-1200 1025);
FORCEPROP 1 LAST LOCATION C357
J 0
(-1500 1025);
DISPLAY 0.489362 (-1500 1025);
PAINT SKYBLUE (-1500 1025);
FORCEPROP 2 LAST $SEC 1
J 0
(-1200 1275);
DISPLAY 0.680851 (-1200 1275);
PAINT MONO (-1200 1275);
DISPLAY INVISIBLE (-1200 1275);
FORCEPROP 2 LAST CDS_SEC 1
J 0
(-1200 1275);
DISPLAY 1.021277 (-1200 1275);
DISPLAY INVISIBLE (-1200 1275);
FORCEPROP 1 LASTPIN (-1300 1025) $PN 1
J 0
(-1310 1040);
DISPLAY 0.489362 (-1310 1040);
PAINT MONO (-1310 1040);
FORCEPROP 1 LASTPIN (-1100 1025) $PN 2
J 0
(-1115 1040);
DISPLAY 0.489362 (-1115 1040);
PAINT MONO (-1115 1040);
FORCEPROP 1 LAST VALUE 0.1UF
J 2
(-825 1025);
DISPLAY 0.489362 (-825 1025);
PAINT SKYBLUE (-825 1025);
FORCEPROP 1 LAST PACK_TYPE C0402
J 1
(-350 975);
DISPLAY 0.978723 (-350 975);
PAINT SKYBLUE (-350 975);
DISPLAY INVISIBLE (-350 975);
FORCEPROP 1 LAST VOLTAGE 16V
J 0
(-675 975);
DISPLAY 0.978723 (-675 975);
PAINT SKYBLUE (-675 975);
DISPLAY INVISIBLE (-675 975);
FORCEPROP 1 LAST TOLERANCE 10%
J 2
(-925 975);
DISPLAY 0.978723 (-925 975);
PAINT SKYBLUE (-925 975);
DISPLAY INVISIBLE (-925 975);
FORCEPROP 1 LAST MATERIAL X7R
J 0
(-850 975);
DISPLAY 0.978723 (-850 975);
PAINT SKYBLUE (-850 975);
DISPLAY INVISIBLE (-850 975);
FORCEPROP 2 LAST CDS_LIB pure_quanta
J 0
(-1200 1025);
DISPLAY INVISIBLE (-1200 1025);
FORCEPROP 1 LAST PATH I106
J 0
(-1200 1225);
DISPLAY 0.978723 (-1200 1225);
PAINT WHITE (-1200 1225);
DISPLAY INVISIBLE (-1200 1225);
FORCEPROP 1 LAST PART_NUMBER CH4103K1B08
J 1
(-450 1025);
DISPLAY 0.978723 (-450 1025);
PAINT SKYBLUE (-450 1025);
DISPLAY INVISIBLE (-450 1025);
FORCEADD Q_CAP..2
(-1200 1125);
FORCEPROP 1 LAST LOCATION C356
J 0
(-1500 1125);
DISPLAY 0.489362 (-1500 1125);
PAINT SKYBLUE (-1500 1125);
FORCEPROP 2 LAST $SEC 1
J 0
(-1200 1375);
DISPLAY 0.680851 (-1200 1375);
PAINT MONO (-1200 1375);
DISPLAY INVISIBLE (-1200 1375);
FORCEPROP 2 LAST CDS_SEC 1
J 0
(-1200 1375);
DISPLAY 1.021277 (-1200 1375);
DISPLAY INVISIBLE (-1200 1375);
FORCEPROP 1 LASTPIN (-1300 1125) $PN 1
J 0
(-1310 1140);
DISPLAY 0.489362 (-1310 1140);
PAINT MONO (-1310 1140);
FORCEPROP 1 LASTPIN (-1100 1125) $PN 2
J 0
(-1115 1140);
DISPLAY 0.489362 (-1115 1140);
PAINT MONO (-1115 1140);
FORCEPROP 1 LAST VALUE 0.1UF
J 2
(-825 1125);
DISPLAY 0.489362 (-825 1125);
PAINT SKYBLUE (-825 1125);
FORCEPROP 1 LAST PACK_TYPE C0402
J 1
(-350 1075);
DISPLAY 0.978723 (-350 1075);
PAINT SKYBLUE (-350 1075);
DISPLAY INVISIBLE (-350 1075);
FORCEPROP 1 LAST VOLTAGE 16V
J 0
(-675 1075);
DISPLAY 0.978723 (-675 1075);
PAINT SKYBLUE (-675 1075);
DISPLAY INVISIBLE (-675 1075);
FORCEPROP 1 LAST TOLERANCE 10%
J 2
(-925 1075);
DISPLAY 0.978723 (-925 1075);
PAINT SKYBLUE (-925 1075);
DISPLAY INVISIBLE (-925 1075);
FORCEPROP 1 LAST MATERIAL X7R
J 0
(-850 1075);
DISPLAY 0.978723 (-850 1075);
PAINT SKYBLUE (-850 1075);
DISPLAY INVISIBLE (-850 1075);
FORCEPROP 2 LAST CDS_LIB pure_quanta
J 0
(-1200 1125);
DISPLAY INVISIBLE (-1200 1125);
FORCEPROP 1 LAST PATH I107
J 0
(-1200 1325);
DISPLAY 0.978723 (-1200 1325);
PAINT WHITE (-1200 1325);
DISPLAY INVISIBLE (-1200 1325);
FORCEPROP 1 LAST PART_NUMBER CH4103K1B08
J 1
(-450 1125);
DISPLAY 0.978723 (-450 1125);
PAINT SKYBLUE (-450 1125);
DISPLAY INVISIBLE (-450 1125);
FORCEADD Q_CAP..2
(-1200 1225);
FORCEPROP 1 LAST LOCATION C355
J 0
(-1500 1225);
DISPLAY 0.489362 (-1500 1225);
PAINT SKYBLUE (-1500 1225);
FORCEPROP 2 LAST $SEC 1
J 0
(-1200 1475);
DISPLAY 0.680851 (-1200 1475);
PAINT MONO (-1200 1475);
DISPLAY INVISIBLE (-1200 1475);
FORCEPROP 2 LAST CDS_SEC 1
J 0
(-1200 1475);
DISPLAY 1.021277 (-1200 1475);
DISPLAY INVISIBLE (-1200 1475);
FORCEPROP 1 LASTPIN (-1300 1225) $PN 1
J 0
(-1310 1240);
DISPLAY 0.489362 (-1310 1240);
PAINT MONO (-1310 1240);
FORCEPROP 1 LASTPIN (-1100 1225) $PN 2
J 0
(-1115 1240);
DISPLAY 0.489362 (-1115 1240);
PAINT MONO (-1115 1240);
FORCEPROP 1 LAST VALUE 0.1UF
J 2
(-825 1225);
DISPLAY 0.489362 (-825 1225);
PAINT SKYBLUE (-825 1225);
FORCEPROP 1 LAST PACK_TYPE C0402
J 1
(-350 1175);
DISPLAY 0.978723 (-350 1175);
PAINT SKYBLUE (-350 1175);
DISPLAY INVISIBLE (-350 1175);
FORCEPROP 1 LAST VOLTAGE 16V
J 0
(-675 1175);
DISPLAY 0.978723 (-675 1175);
PAINT SKYBLUE (-675 1175);
DISPLAY INVISIBLE (-675 1175);
FORCEPROP 1 LAST TOLERANCE 10%
J 2
(-925 1175);
DISPLAY 0.978723 (-925 1175);
PAINT SKYBLUE (-925 1175);
DISPLAY INVISIBLE (-925 1175);
FORCEPROP 1 LAST MATERIAL X7R
J 0
(-850 1175);
DISPLAY 0.978723 (-850 1175);
PAINT SKYBLUE (-850 1175);
DISPLAY INVISIBLE (-850 1175);
FORCEPROP 2 LAST CDS_LIB pure_quanta
J 0
(-1200 1225);
DISPLAY INVISIBLE (-1200 1225);
FORCEPROP 1 LAST PATH I108
J 0
(-1200 1425);
DISPLAY 0.978723 (-1200 1425);
PAINT WHITE (-1200 1425);
DISPLAY INVISIBLE (-1200 1425);
FORCEPROP 1 LAST PART_NUMBER CH4103K1B08
J 1
(-450 1225);
DISPLAY 0.978723 (-450 1225);
PAINT SKYBLUE (-450 1225);
DISPLAY INVISIBLE (-450 1225);
FORCEADD Q_CAP..2
(-1200 1325);
FORCEPROP 1 LAST LOCATION C1176
J 0
(-1500 1325);
DISPLAY 0.489362 (-1500 1325);
PAINT SKYBLUE (-1500 1325);
FORCEPROP 0 LAST $SEC 1
J 0
(-825 1375);
DISPLAY 0.680851 (-825 1375);
PAINT MONO (-825 1375);
DISPLAY INVISIBLE (-825 1375);
FORCEPROP 0 LAST CDS_SEC 1
J 0
(-825 1375);
DISPLAY 1.021277 (-825 1375);
DISPLAY INVISIBLE (-825 1375);
FORCEPROP 1 LASTPIN (-1300 1325) $PN 1
J 0
(-1310 1340);
DISPLAY 0.489362 (-1310 1340);
PAINT MONO (-1310 1340);
FORCEPROP 1 LASTPIN (-1100 1325) $PN 2
J 0
(-1115 1340);
DISPLAY 0.489362 (-1115 1340);
PAINT MONO (-1115 1340);
FORCEPROP 1 LAST VALUE 0.1UF
J 2
(-825 1325);
DISPLAY 0.489362 (-825 1325);
PAINT SKYBLUE (-825 1325);
FORCEPROP 1 LAST PACK_TYPE C0402
J 1
(-350 1275);
DISPLAY 0.978723 (-350 1275);
PAINT SKYBLUE (-350 1275);
DISPLAY INVISIBLE (-350 1275);
FORCEPROP 1 LAST VOLTAGE 16V
J 0
(-675 1275);
DISPLAY 0.978723 (-675 1275);
PAINT SKYBLUE (-675 1275);
DISPLAY INVISIBLE (-675 1275);
FORCEPROP 1 LAST TOLERANCE 10%
J 2
(-925 1275);
DISPLAY 0.978723 (-925 1275);
PAINT SKYBLUE (-925 1275);
DISPLAY INVISIBLE (-925 1275);
FORCEPROP 1 LAST MATERIAL X7R
J 0
(-850 1275);
DISPLAY 0.978723 (-850 1275);
PAINT SKYBLUE (-850 1275);
DISPLAY INVISIBLE (-850 1275);
FORCEPROP 2 LAST CDS_LIB pure_quanta
J 0
(-1200 1325);
DISPLAY INVISIBLE (-1200 1325);
FORCEPROP 1 LAST PATH I109
J 0
(-1200 1525);
DISPLAY 0.978723 (-1200 1525);
PAINT WHITE (-1200 1525);
DISPLAY INVISIBLE (-1200 1525);
FORCEPROP 1 LAST PART_NUMBER CH4103K1B08
J 1
(-450 1325);
DISPLAY 0.978723 (-450 1325);
PAINT SKYBLUE (-450 1325);
DISPLAY INVISIBLE (-450 1325);
FORCEADD OFFPAGE..5
(-8225 3950);
FORCEPROP 2 LAST $XR2 147 
J 0
(-8689 3950);
DISPLAY 0.638298 (-8689 3950);
PAINT MONO (-8689 3950);
FORCEPROP 2 LAST $XR1 146 
J 0
(-8569 3950);
DISPLAY 0.638298 (-8569 3950);
PAINT MONO (-8569 3950);
FORCEPROP 2 LAST $XR0 81 
J 0
(-8449 3950);
DISPLAY 0.638298 (-8449 3950);
PAINT MONO (-8449 3950);
FORCEPROP 2 LAST CDS_LIB standard
J 0
(-8225 3950);
DISPLAY INVISIBLE (-8225 3950);
FORCEPROP 1 LAST OFFPAGE TRUE
J 0
(-7900 3825);
DISPLAY 0.872340 (-7900 3825);
PAINT GREEN (-7900 3825);
DISPLAY INVISIBLE (-7900 3825);
FORCEPROP 1 LAST COMMENT_BODY TRUE
J 0
(-8125 3875);
DISPLAY 0.872340 (-8125 3875);
PAINT GREEN (-8125 3875);
DISPLAY INVISIBLE (-8125 3875);
FORCEPROP 2 LAST PATH I11
J 0
(-8475 4000);
DISPLAY 0.680851 (-8475 4000);
DISPLAY INVISIBLE (-8475 4000);
FORCEADD Q_CAP..2
(-1200 1425);
FORCEPROP 1 LAST LOCATION C1175
J 0
(-1500 1425);
DISPLAY 0.489362 (-1500 1425);
PAINT SKYBLUE (-1500 1425);
FORCEPROP 0 LAST $SEC 1
J 0
(-825 1475);
DISPLAY 0.680851 (-825 1475);
PAINT MONO (-825 1475);
DISPLAY INVISIBLE (-825 1475);
FORCEPROP 0 LAST CDS_SEC 1
J 0
(-825 1475);
DISPLAY 1.021277 (-825 1475);
DISPLAY INVISIBLE (-825 1475);
FORCEPROP 1 LASTPIN (-1300 1425) $PN 1
J 0
(-1310 1440);
DISPLAY 0.489362 (-1310 1440);
PAINT MONO (-1310 1440);
FORCEPROP 1 LASTPIN (-1100 1425) $PN 2
J 0
(-1115 1440);
DISPLAY 0.489362 (-1115 1440);
PAINT MONO (-1115 1440);
FORCEPROP 1 LAST VALUE 0.1UF
J 2
(-825 1425);
DISPLAY 0.489362 (-825 1425);
PAINT SKYBLUE (-825 1425);
FORCEPROP 1 LAST PACK_TYPE C0402
J 1
(-350 1375);
DISPLAY 0.978723 (-350 1375);
PAINT SKYBLUE (-350 1375);
DISPLAY INVISIBLE (-350 1375);
FORCEPROP 1 LAST VOLTAGE 16V
J 0
(-675 1375);
DISPLAY 0.978723 (-675 1375);
PAINT SKYBLUE (-675 1375);
DISPLAY INVISIBLE (-675 1375);
FORCEPROP 1 LAST TOLERANCE 10%
J 2
(-925 1375);
DISPLAY 0.978723 (-925 1375);
PAINT SKYBLUE (-925 1375);
DISPLAY INVISIBLE (-925 1375);
FORCEPROP 1 LAST MATERIAL X7R
J 0
(-850 1375);
DISPLAY 0.978723 (-850 1375);
PAINT SKYBLUE (-850 1375);
DISPLAY INVISIBLE (-850 1375);
FORCEPROP 2 LAST CDS_LIB pure_quanta
J 0
(-1200 1425);
DISPLAY INVISIBLE (-1200 1425);
FORCEPROP 1 LAST PATH I110
J 0
(-1200 1625);
DISPLAY 0.978723 (-1200 1625);
PAINT WHITE (-1200 1625);
DISPLAY INVISIBLE (-1200 1625);
FORCEPROP 1 LAST PART_NUMBER CH4103K1B08
J 1
(-450 1425);
DISPLAY 0.978723 (-450 1425);
PAINT SKYBLUE (-450 1425);
DISPLAY INVISIBLE (-450 1425);
FORCEADD Q_CAP..2
(-1200 1525);
FORCEPROP 1 LAST LOCATION C1174
J 0
(-1500 1525);
DISPLAY 0.489362 (-1500 1525);
PAINT SKYBLUE (-1500 1525);
FORCEPROP 0 LAST $SEC 1
J 0
(-825 1575);
DISPLAY 0.680851 (-825 1575);
PAINT MONO (-825 1575);
DISPLAY INVISIBLE (-825 1575);
FORCEPROP 0 LAST CDS_SEC 1
J 0
(-825 1575);
DISPLAY 1.021277 (-825 1575);
DISPLAY INVISIBLE (-825 1575);
FORCEPROP 1 LASTPIN (-1300 1525) $PN 1
J 0
(-1310 1540);
DISPLAY 0.489362 (-1310 1540);
PAINT MONO (-1310 1540);
FORCEPROP 1 LASTPIN (-1100 1525) $PN 2
J 0
(-1115 1540);
DISPLAY 0.489362 (-1115 1540);
PAINT MONO (-1115 1540);
FORCEPROP 1 LAST VALUE 0.1UF
J 2
(-825 1525);
DISPLAY 0.489362 (-825 1525);
PAINT SKYBLUE (-825 1525);
FORCEPROP 1 LAST PACK_TYPE C0402
J 1
(-350 1475);
DISPLAY 0.978723 (-350 1475);
PAINT SKYBLUE (-350 1475);
DISPLAY INVISIBLE (-350 1475);
FORCEPROP 1 LAST VOLTAGE 16V
J 0
(-675 1475);
DISPLAY 0.978723 (-675 1475);
PAINT SKYBLUE (-675 1475);
DISPLAY INVISIBLE (-675 1475);
FORCEPROP 1 LAST TOLERANCE 10%
J 2
(-925 1475);
DISPLAY 0.978723 (-925 1475);
PAINT SKYBLUE (-925 1475);
DISPLAY INVISIBLE (-925 1475);
FORCEPROP 1 LAST MATERIAL X7R
J 0
(-850 1475);
DISPLAY 0.978723 (-850 1475);
PAINT SKYBLUE (-850 1475);
DISPLAY INVISIBLE (-850 1475);
FORCEPROP 2 LAST CDS_LIB pure_quanta
J 0
(-1200 1525);
DISPLAY INVISIBLE (-1200 1525);
FORCEPROP 1 LAST PATH I111
J 0
(-1200 1725);
DISPLAY 0.978723 (-1200 1725);
PAINT WHITE (-1200 1725);
DISPLAY INVISIBLE (-1200 1725);
FORCEPROP 1 LAST PART_NUMBER CH4103K1B08
J 1
(-450 1525);
DISPLAY 0.978723 (-450 1525);
PAINT SKYBLUE (-450 1525);
DISPLAY INVISIBLE (-450 1525);
FORCEADD Q_CAP..2
(-1200 1725);
FORCEPROP 1 LAST LOCATION C1172
J 0
(-1500 1725);
DISPLAY 0.489362 (-1500 1725);
PAINT SKYBLUE (-1500 1725);
FORCEPROP 0 LAST $SEC 1
J 0
(-825 1775);
DISPLAY 0.680851 (-825 1775);
PAINT MONO (-825 1775);
DISPLAY INVISIBLE (-825 1775);
FORCEPROP 0 LAST CDS_SEC 1
J 0
(-825 1775);
DISPLAY 1.021277 (-825 1775);
DISPLAY INVISIBLE (-825 1775);
FORCEPROP 1 LASTPIN (-1300 1725) $PN 1
J 0
(-1310 1740);
DISPLAY 0.489362 (-1310 1740);
PAINT MONO (-1310 1740);
FORCEPROP 1 LASTPIN (-1100 1725) $PN 2
J 0
(-1115 1740);
DISPLAY 0.489362 (-1115 1740);
PAINT MONO (-1115 1740);
FORCEPROP 1 LAST VALUE 0.1UF
J 2
(-825 1725);
DISPLAY 0.489362 (-825 1725);
PAINT SKYBLUE (-825 1725);
FORCEPROP 1 LAST PACK_TYPE C0402
J 1
(-350 1675);
DISPLAY 0.978723 (-350 1675);
PAINT SKYBLUE (-350 1675);
DISPLAY INVISIBLE (-350 1675);
FORCEPROP 1 LAST VOLTAGE 16V
J 0
(-675 1675);
DISPLAY 0.978723 (-675 1675);
PAINT SKYBLUE (-675 1675);
DISPLAY INVISIBLE (-675 1675);
FORCEPROP 1 LAST TOLERANCE 10%
J 2
(-925 1675);
DISPLAY 0.978723 (-925 1675);
PAINT SKYBLUE (-925 1675);
DISPLAY INVISIBLE (-925 1675);
FORCEPROP 1 LAST MATERIAL X7R
J 0
(-850 1675);
DISPLAY 0.978723 (-850 1675);
PAINT SKYBLUE (-850 1675);
DISPLAY INVISIBLE (-850 1675);
FORCEPROP 2 LAST CDS_LIB pure_quanta
J 0
(-1200 1725);
DISPLAY INVISIBLE (-1200 1725);
FORCEPROP 1 LAST PATH I112
J 0
(-1200 1925);
DISPLAY 0.978723 (-1200 1925);
PAINT WHITE (-1200 1925);
DISPLAY INVISIBLE (-1200 1925);
FORCEPROP 1 LAST PART_NUMBER CH4103K1B08
J 1
(-450 1725);
DISPLAY 0.978723 (-450 1725);
PAINT SKYBLUE (-450 1725);
DISPLAY INVISIBLE (-450 1725);
FORCEADD Q_CAP..2
(-1200 1625);
FORCEPROP 1 LAST LOCATION C1173
J 0
(-1500 1625);
DISPLAY 0.489362 (-1500 1625);
PAINT SKYBLUE (-1500 1625);
FORCEPROP 0 LAST $SEC 1
J 0
(-450 1675);
DISPLAY 0.680851 (-450 1675);
PAINT MONO (-450 1675);
DISPLAY INVISIBLE (-450 1675);
FORCEPROP 0 LAST CDS_SEC 1
J 0
(-450 1675);
DISPLAY 1.021277 (-450 1675);
DISPLAY INVISIBLE (-450 1675);
FORCEPROP 1 LASTPIN (-1300 1625) $PN 1
J 0
(-1310 1640);
DISPLAY 0.489362 (-1310 1640);
PAINT MONO (-1310 1640);
FORCEPROP 1 LASTPIN (-1100 1625) $PN 2
J 0
(-1115 1640);
DISPLAY 0.489362 (-1115 1640);
PAINT MONO (-1115 1640);
FORCEPROP 1 LAST VALUE 0.1UF
J 2
(-825 1625);
DISPLAY 0.489362 (-825 1625);
PAINT SKYBLUE (-825 1625);
FORCEPROP 1 LAST PACK_TYPE C0402
J 1
(-750 1575);
DISPLAY 0.489362 (-750 1575);
PAINT SKYBLUE (-750 1575);
DISPLAY INVISIBLE (-750 1575);
FORCEPROP 1 LAST VOLTAGE 16V
J 0
(-800 1600);
DISPLAY 0.489362 (-800 1600);
PAINT SKYBLUE (-800 1600);
DISPLAY INVISIBLE (-800 1600);
FORCEPROP 1 LAST TOLERANCE 10%
J 2
(-925 1600);
DISPLAY 0.489362 (-925 1600);
PAINT SKYBLUE (-925 1600);
DISPLAY INVISIBLE (-925 1600);
FORCEPROP 1 LAST MATERIAL X7R
J 0
(-1000 1575);
DISPLAY 0.489362 (-1000 1575);
PAINT SKYBLUE (-1000 1575);
DISPLAY INVISIBLE (-1000 1575);
FORCEPROP 2 LAST CDS_LIB pure_quanta
J 0
(-1200 1625);
DISPLAY INVISIBLE (-1200 1625);
FORCEPROP 1 LAST PATH I113
J 0
(-1200 1825);
DISPLAY 0.978723 (-1200 1825);
PAINT WHITE (-1200 1825);
DISPLAY INVISIBLE (-1200 1825);
FORCEPROP 1 LAST PART_NUMBER CH4103K1B08
J 1
(-575 1625);
DISPLAY 0.489362 (-575 1625);
PAINT SKYBLUE (-575 1625);
DISPLAY INVISIBLE (-575 1625);
FORCEADD Q_CAP..2
(-1200 1825);
FORCEPROP 1 LAST LOCATION C1171
J 0
(-1500 1825);
DISPLAY 0.489362 (-1500 1825);
PAINT SKYBLUE (-1500 1825);
FORCEPROP 0 LAST $SEC 1
J 0
(-450 1875);
DISPLAY 0.680851 (-450 1875);
PAINT MONO (-450 1875);
DISPLAY INVISIBLE (-450 1875);
FORCEPROP 0 LAST CDS_SEC 1
J 0
(-450 1875);
DISPLAY 1.021277 (-450 1875);
DISPLAY INVISIBLE (-450 1875);
FORCEPROP 1 LASTPIN (-1300 1825) $PN 1
J 0
(-1310 1840);
DISPLAY 0.489362 (-1310 1840);
PAINT MONO (-1310 1840);
FORCEPROP 1 LASTPIN (-1100 1825) $PN 2
J 0
(-1115 1840);
DISPLAY 0.489362 (-1115 1840);
PAINT MONO (-1115 1840);
FORCEPROP 1 LAST PACK_TYPE C0402
J 1
(-675 1825);
DISPLAY 0.489362 (-675 1825);
PAINT SKYBLUE (-675 1825);
FORCEPROP 1 LAST VOLTAGE 16V
J 0
(-825 1825);
DISPLAY 0.489362 (-825 1825);
PAINT SKYBLUE (-825 1825);
FORCEPROP 1 LAST VALUE 0.1UF
J 2
(-850 1825);
DISPLAY 0.489362 (-850 1825);
PAINT SKYBLUE (-850 1825);
FORCEPROP 1 LAST TOLERANCE 10%
J 2
(-900 1800);
DISPLAY 0.489362 (-900 1800);
PAINT SKYBLUE (-900 1800);
FORCEPROP 1 LAST MATERIAL X7R
J 0
(-825 1800);
DISPLAY 0.489362 (-825 1800);
PAINT SKYBLUE (-825 1800);
FORCEPROP 2 LAST CDS_LIB pure_quanta
J 0
(-1200 1825);
DISPLAY INVISIBLE (-1200 1825);
FORCEPROP 1 LAST PATH I114
J 0
(-1200 2025);
DISPLAY 0.978723 (-1200 2025);
PAINT WHITE (-1200 2025);
DISPLAY INVISIBLE (-1200 2025);
FORCEPROP 1 LAST PART_NUMBER CH4103K1B08
J 1
(-425 1825);
DISPLAY 0.489362 (-425 1825);
PAINT SKYBLUE (-425 1825);
DISPLAY INVISIBLE (-425 1825);
FORCEADD GND..1
(-375 475);
FORCEPROP 3 LASTPIN (-375 525) SIG_NAME GND\g
J 0
(-365 535);
DISPLAY 0.659574 (-365 535);
PAINT MONO (-365 535);
DISPLAY INVISIBLE (-365 535);
FORCEPROP 2 LAST CDS_LIB pure_quanta_power
J 0
(-375 475);
DISPLAY INVISIBLE (-375 475);
FORCEPROP 2 LAST BOM_COST MEM
J 0
(-475 550);
DISPLAY 0.808511 (-475 550);
DISPLAY INVISIBLE (-475 550);
FORCEPROP 1 LAST SIZE 1B
J 0
(-300 425);
DISPLAY 0.851064 (-300 425);
PAINT GREEN (-300 425);
DISPLAY INVISIBLE (-300 425);
FORCEPROP 1 LAST HDL_POWER GND
J 0
(-375 625);
DISPLAY 0.851064 (-375 625);
PAINT GREEN (-375 625);
DISPLAY INVISIBLE (-375 625);
FORCEPROP 1 LAST PATH I115
J 0
(-300 475);
DISPLAY 0.872340 (-300 475);
PAINT AQUA (-300 475);
DISPLAY INVISIBLE (-300 475);
FORCEADD VCC_CORE..1
(-1575 2150);
FORCEPROP 3 LASTPIN (-1575 2100) SIG_NAME P3V3_AUX\g
J 0
(-1565 2110);
DISPLAY 0.659574 (-1565 2110);
PAINT MONO (-1565 2110);
DISPLAY INVISIBLE (-1565 2110);
FORCEPROP 1 LAST HDL_POWER P3V3_AUX
J 1
(-1575 2200);
DISPLAY 0.489362 (-1575 2200);
PAINT GREEN (-1575 2200);
FORCEPROP 2 LAST CDS_LIB pure_quanta_power
J 0
(-1575 2150);
DISPLAY INVISIBLE (-1575 2150);
FORCEPROP 1 LAST PATH I116
J 0
(-1525 2175);
DISPLAY 0.872340 (-1525 2175);
PAINT AQUA (-1525 2175);
DISPLAY INVISIBLE (-1525 2175);
FORCEADD GND..1
(-3625 4250);
FORCEPROP 3 LASTPIN (-3625 4300) SIG_NAME GND\g
J 0
(-3615 4310);
DISPLAY 0.659574 (-3615 4310);
PAINT MONO (-3615 4310);
DISPLAY INVISIBLE (-3615 4310);
FORCEPROP 2 LAST CDS_LIB pure_quanta_power
J 0
(-3625 4250);
DISPLAY INVISIBLE (-3625 4250);
FORCEPROP 1 LAST SIZE 1B
J 0
(-3550 4200);
DISPLAY 0.851064 (-3550 4200);
PAINT GREEN (-3550 4200);
DISPLAY INVISIBLE (-3550 4200);
FORCEPROP 2 LAST BOM_COST MEM
J 0
(-3725 4325);
DISPLAY 0.808511 (-3725 4325);
DISPLAY INVISIBLE (-3725 4325);
FORCEPROP 1 LAST HDL_POWER GND
J 0
(-3625 4400);
DISPLAY 0.851064 (-3625 4400);
PAINT GREEN (-3625 4400);
DISPLAY INVISIBLE (-3625 4400);
FORCEPROP 1 LAST PATH I117
J 0
(-3550 4250);
DISPLAY 0.872340 (-3550 4250);
PAINT AQUA (-3550 4250);
DISPLAY INVISIBLE (-3550 4250);
FORCEADD Q_RES..2
(-3625 4475);
FORCEPROP 1 LAST LOCATION R800
J 0
(-3580 4600);
DISPLAY 0.489362 (-3580 4600);
PAINT SKYBLUE (-3580 4600);
FORCEPROP 2 LAST $SEC 1
J 0
(-3575 4700);
DISPLAY 0.680851 (-3575 4700);
PAINT MONO (-3575 4700);
DISPLAY INVISIBLE (-3575 4700);
FORCEPROP 2 LAST CDS_SEC 1
J 0
(-3575 4700);
DISPLAY 1.021277 (-3575 4700);
DISPLAY INVISIBLE (-3575 4700);
FORCEPROP 1 LASTPIN (-3625 4575) $PN 1
J 0
(-3620 4537);
DISPLAY 0.489362 (-3620 4537);
PAINT MONO (-3620 4537);
FORCEPROP 1 LASTPIN (-3625 4375) $PN 2
J 0
(-3620 4385);
DISPLAY 0.489362 (-3620 4385);
PAINT MONO (-3620 4385);
FORCEPROP 1 LAST VALUE 10K
J 0
(-3600 4550);
DISPLAY 0.489362 (-3600 4550);
PAINT SKYBLUE (-3600 4550);
FORCEPROP 1 LAST MATERIAL CHIP
J 0
(-3600 4400);
DISPLAY 0.489362 (-3600 4400);
PAINT SKYBLUE (-3600 4400);
FORCEPROP 1 LAST WATTAGE 1/16W
J 0
(-3600 4450);
DISPLAY 0.489362 (-3600 4450);
PAINT SKYBLUE (-3600 4450);
FORCEPROP 1 LAST TOLERANCE 1%
J 0
(-3600 4500);
DISPLAY 0.489362 (-3600 4500);
PAINT SKYBLUE (-3600 4500);
FORCEPROP 1 LAST PACK_TYPE 0402LF
J 0
(-3600 4350);
DISPLAY 0.489362 (-3600 4350);
PAINT SKYBLUE (-3600 4350);
FORCEPROP 2 LAST CDS_LIB pure_quanta
J 0
(-3625 4475);
DISPLAY INVISIBLE (-3625 4475);
FORCEPROP 2 LAST BOM_COST MEM
J 0
(-3575 4650);
DISPLAY 0.808511 (-3575 4650);
DISPLAY INVISIBLE (-3575 4650);
FORCEPROP 1 LAST PATH I118
J 0
(-3575 4650);
DISPLAY 0.978723 (-3575 4650);
PAINT WHITE (-3575 4650);
DISPLAY INVISIBLE (-3575 4650);
FORCEPROP 1 LAST PART_NUMBER CS31002FB08
J 0
(-3585 4350);
DISPLAY 0.489362 (-3585 4350);
PAINT SKYBLUE (-3585 4350);
DISPLAY INVISIBLE (-3585 4350);
FORCEADD GND..1
(-3425 4250);
FORCEPROP 3 LASTPIN (-3425 4300) SIG_NAME GND\g
J 0
(-3415 4310);
DISPLAY 0.659574 (-3415 4310);
PAINT MONO (-3415 4310);
DISPLAY INVISIBLE (-3415 4310);
FORCEPROP 1 LAST VOLTAGE 0.0
J 0
(-3470 4207);
DISPLAY 0.723404 (-3470 4207);
PAINT SKYBLUE (-3470 4207);
DISPLAY INVISIBLE (-3470 4207);
FORCEPROP 2 LAST CDS_LIB mstr_symbols
J 0
(-3425 4250);
DISPLAY INVISIBLE (-3425 4250);
FORCEPROP 1 LAST SIZE 1B
J 0
(-3350 4200);
DISPLAY 0.851064 (-3350 4200);
PAINT GREEN (-3350 4200);
DISPLAY INVISIBLE (-3350 4200);
FORCEPROP 2 LAST BOM_COST MEM
J 0
(-3525 4325);
DISPLAY 0.808511 (-3525 4325);
DISPLAY INVISIBLE (-3525 4325);
FORCEPROP 1 LAST BODY_TYPE PLUMBING
J 0
(-3470 4207);
DISPLAY 0.340426 (-3470 4207);
PAINT GREEN (-3470 4207);
DISPLAY INVISIBLE (-3470 4207);
FORCEPROP 1 LAST HDL_POWER GND
J 0
(-3425 4400);
DISPLAY 0.851064 (-3425 4400);
PAINT GREEN (-3425 4400);
DISPLAY INVISIBLE (-3425 4400);
FORCEPROP 1 LAST PATH I119
J 0
(-3350 4250);
DISPLAY 0.872340 (-3350 4250);
PAINT AQUA (-3350 4250);
DISPLAY INVISIBLE (-3350 4250);
FORCEADD OFFPAGE..5
(-8225 4200);
FORCEPROP 2 LAST $XR2 147 
J 0
(-8689 4200);
DISPLAY 0.638298 (-8689 4200);
PAINT MONO (-8689 4200);
FORCEPROP 2 LAST $XR1 146 
J 0
(-8569 4200);
DISPLAY 0.638298 (-8569 4200);
PAINT MONO (-8569 4200);
FORCEPROP 2 LAST $XR0 81 
J 0
(-8449 4200);
DISPLAY 0.638298 (-8449 4200);
PAINT MONO (-8449 4200);
FORCEPROP 2 LAST CDS_LIB standard
J 0
(-8225 4200);
DISPLAY INVISIBLE (-8225 4200);
FORCEPROP 1 LAST OFFPAGE TRUE
J 0
(-7900 4075);
DISPLAY 0.872340 (-7900 4075);
PAINT GREEN (-7900 4075);
DISPLAY INVISIBLE (-7900 4075);
FORCEPROP 1 LAST COMMENT_BODY TRUE
J 0
(-8125 4125);
DISPLAY 0.872340 (-8125 4125);
PAINT GREEN (-8125 4125);
DISPLAY INVISIBLE (-8125 4125);
FORCEPROP 2 LAST PATH I12
J 0
(-8475 4250);
DISPLAY 0.680851 (-8475 4250);
DISPLAY INVISIBLE (-8475 4250);
FORCEADD Q_RES..2
(-3425 4475);
FORCEPROP 1 LAST LOCATION R804
J 0
(-3380 4600);
DISPLAY 0.489362 (-3380 4600);
PAINT SKYBLUE (-3380 4600);
FORCEPROP 2 LAST $SEC 1
J 0
(-3375 4700);
DISPLAY 0.680851 (-3375 4700);
PAINT MONO (-3375 4700);
DISPLAY INVISIBLE (-3375 4700);
FORCEPROP 2 LAST CDS_SEC 1
J 0
(-3375 4700);
DISPLAY 1.021277 (-3375 4700);
DISPLAY INVISIBLE (-3375 4700);
FORCEPROP 1 LASTPIN (-3425 4575) $PN 1
J 0
(-3420 4537);
DISPLAY 0.489362 (-3420 4537);
PAINT MONO (-3420 4537);
FORCEPROP 1 LASTPIN (-3425 4375) $PN 2
J 0
(-3420 4385);
DISPLAY 0.489362 (-3420 4385);
PAINT MONO (-3420 4385);
FORCEPROP 1 LAST WATTAGE 1/16W
J 0
(-3400 4450);
DISPLAY 0.489362 (-3400 4450);
PAINT SKYBLUE (-3400 4450);
FORCEPROP 1 LAST MATERIAL CHIP
J 0
(-3400 4400);
DISPLAY 0.489362 (-3400 4400);
PAINT SKYBLUE (-3400 4400);
FORCEPROP 1 LAST TOLERANCE 1%
J 0
(-3400 4500);
DISPLAY 0.489362 (-3400 4500);
PAINT SKYBLUE (-3400 4500);
FORCEPROP 1 LAST VALUE 10K
J 0
(-3400 4550);
DISPLAY 0.489362 (-3400 4550);
PAINT SKYBLUE (-3400 4550);
FORCEPROP 1 LAST PACK_TYPE 0402LF
J 0
(-3400 4350);
DISPLAY 0.489362 (-3400 4350);
PAINT SKYBLUE (-3400 4350);
FORCEPROP 2 LAST CDS_LIB pure_quanta
J 0
(-3425 4475);
DISPLAY INVISIBLE (-3425 4475);
FORCEPROP 2 LAST BOM_COST MEM
J 0
(-3375 4650);
DISPLAY 0.808511 (-3375 4650);
DISPLAY INVISIBLE (-3375 4650);
FORCEPROP 1 LAST PATH I120
J 0
(-3375 4650);
DISPLAY 0.978723 (-3375 4650);
PAINT WHITE (-3375 4650);
DISPLAY INVISIBLE (-3375 4650);
FORCEPROP 1 LAST PART_NUMBER CS31002FB08
J 0
(-3385 4350);
DISPLAY 0.489362 (-3385 4350);
PAINT SKYBLUE (-3385 4350);
DISPLAY INVISIBLE (-3385 4350);
FORCEADD GND..1
(-3500 5575);
FORCEPROP 3 LASTPIN (-3500 5625) SIG_NAME GND\g
J 0
(-3490 5635);
DISPLAY 0.659574 (-3490 5635);
PAINT MONO (-3490 5635);
DISPLAY INVISIBLE (-3490 5635);
FORCEPROP 2 LAST BOM_COST MEM
J 0
(-3600 5650);
DISPLAY 0.808511 (-3600 5650);
DISPLAY INVISIBLE (-3600 5650);
FORCEPROP 1 LAST SIZE 1B
J 0
(-3425 5525);
DISPLAY 0.851064 (-3425 5525);
PAINT GREEN (-3425 5525);
DISPLAY INVISIBLE (-3425 5525);
FORCEPROP 2 LAST CDS_LIB pure_quanta_power
J 0
(-3500 5575);
DISPLAY INVISIBLE (-3500 5575);
FORCEPROP 1 LAST HDL_POWER GND
J 0
(-3500 5725);
DISPLAY 0.851064 (-3500 5725);
PAINT GREEN (-3500 5725);
DISPLAY INVISIBLE (-3500 5725);
FORCEPROP 1 LAST PATH I121
J 0
(-3425 5575);
DISPLAY 0.872340 (-3425 5575);
PAINT AQUA (-3425 5575);
DISPLAY INVISIBLE (-3425 5575);
FORCEADD GND..1
(-3300 5575);
FORCEPROP 3 LASTPIN (-3300 5625) SIG_NAME GND\g
J 0
(-3290 5635);
DISPLAY 0.659574 (-3290 5635);
PAINT MONO (-3290 5635);
DISPLAY INVISIBLE (-3290 5635);
FORCEPROP 2 LAST BOM_COST MEM
J 0
(-3400 5650);
DISPLAY 0.808511 (-3400 5650);
DISPLAY INVISIBLE (-3400 5650);
FORCEPROP 1 LAST SIZE 1B
J 0
(-3225 5525);
DISPLAY 0.851064 (-3225 5525);
PAINT GREEN (-3225 5525);
DISPLAY INVISIBLE (-3225 5525);
FORCEPROP 2 LAST CDS_LIB pure_quanta_power
J 0
(-3300 5575);
DISPLAY INVISIBLE (-3300 5575);
FORCEPROP 1 LAST HDL_POWER GND
J 0
(-3300 5725);
DISPLAY 0.851064 (-3300 5725);
PAINT GREEN (-3300 5725);
DISPLAY INVISIBLE (-3300 5725);
FORCEPROP 1 LAST PATH I122
J 0
(-3225 5575);
DISPLAY 0.872340 (-3225 5575);
PAINT AQUA (-3225 5575);
DISPLAY INVISIBLE (-3225 5575);
FORCEADD GND..1
(-3100 5575);
FORCEPROP 3 LASTPIN (-3100 5625) SIG_NAME GND\g
J 0
(-3090 5635);
DISPLAY 0.659574 (-3090 5635);
PAINT MONO (-3090 5635);
DISPLAY INVISIBLE (-3090 5635);
FORCEPROP 1 LAST VOLTAGE 0.0
J 0
(-3145 5532);
DISPLAY 0.723404 (-3145 5532);
PAINT SKYBLUE (-3145 5532);
DISPLAY INVISIBLE (-3145 5532);
FORCEPROP 1 LAST SIZE 1B
J 0
(-3025 5525);
DISPLAY 0.851064 (-3025 5525);
PAINT GREEN (-3025 5525);
DISPLAY INVISIBLE (-3025 5525);
FORCEPROP 2 LAST BOM_COST MEM
J 0
(-3200 5650);
DISPLAY 0.808511 (-3200 5650);
DISPLAY INVISIBLE (-3200 5650);
FORCEPROP 2 LAST CDS_LIB mstr_symbols
J 0
(-3100 5575);
DISPLAY INVISIBLE (-3100 5575);
FORCEPROP 1 LAST BODY_TYPE PLUMBING
J 0
(-3145 5532);
DISPLAY 0.340426 (-3145 5532);
PAINT GREEN (-3145 5532);
DISPLAY INVISIBLE (-3145 5532);
FORCEPROP 1 LAST HDL_POWER GND
J 0
(-3100 5725);
DISPLAY 0.851064 (-3100 5725);
PAINT GREEN (-3100 5725);
DISPLAY INVISIBLE (-3100 5725);
FORCEPROP 1 LAST PATH I123
J 0
(-3025 5575);
DISPLAY 0.872340 (-3025 5575);
PAINT AQUA (-3025 5575);
DISPLAY INVISIBLE (-3025 5575);
FORCEADD Q_RES..2
(-3500 5800);
FORCEPROP 1 LAST LOCATION R16
J 0
(-3475 5925);
DISPLAY 0.489362 (-3475 5925);
PAINT SKYBLUE (-3475 5925);
FORCEPROP 0 LAST $SEC 1
J 0
(-3450 5975);
DISPLAY 0.680851 (-3450 5975);
PAINT MONO (-3450 5975);
DISPLAY INVISIBLE (-3450 5975);
FORCEPROP 0 LAST CDS_SEC 1
J 0
(-3450 5975);
DISPLAY 1.021277 (-3450 5975);
DISPLAY INVISIBLE (-3450 5975);
FORCEPROP 1 LASTPIN (-3500 5900) $PN 1
J 0
(-3495 5862);
DISPLAY 0.489362 (-3495 5862);
PAINT MONO (-3495 5862);
FORCEPROP 1 LASTPIN (-3500 5700) $PN 2
J 0
(-3495 5710);
DISPLAY 0.489362 (-3495 5710);
PAINT MONO (-3495 5710);
FORCEPROP 1 LAST TOLERANCE 1%
J 0
(-3455 5825);
DISPLAY 0.489362 (-3455 5825);
PAINT SKYBLUE (-3455 5825);
FORCEPROP 1 LAST VALUE 10K
J 0
(-3455 5875);
DISPLAY 0.489362 (-3455 5875);
PAINT SKYBLUE (-3455 5875);
FORCEPROP 1 LAST PACK_TYPE 0402LF
J 0
(-3450 5675);
DISPLAY 0.489362 (-3450 5675);
PAINT SKYBLUE (-3450 5675);
FORCEPROP 1 LAST MATERIAL CHIP
J 0
(-3460 5725);
DISPLAY 0.489362 (-3460 5725);
PAINT SKYBLUE (-3460 5725);
FORCEPROP 1 LAST WATTAGE 1/16W
J 0
(-3460 5775);
DISPLAY 0.489362 (-3460 5775);
PAINT SKYBLUE (-3460 5775);
FORCEPROP 2 LAST BOM_COST MEM
J 0
(-3450 5975);
DISPLAY 0.808511 (-3450 5975);
DISPLAY INVISIBLE (-3450 5975);
FORCEPROP 2 LAST CDS_LIB pure_quanta
J 0
(-3500 5800);
DISPLAY INVISIBLE (-3500 5800);
FORCEPROP 1 LAST PATH I124
J 0
(-3450 5975);
DISPLAY 0.978723 (-3450 5975);
PAINT WHITE (-3450 5975);
DISPLAY INVISIBLE (-3450 5975);
FORCEPROP 1 LAST PART_NUMBER CS31002FB08
J 0
(-3460 5675);
DISPLAY 0.489362 (-3460 5675);
PAINT SKYBLUE (-3460 5675);
DISPLAY INVISIBLE (-3460 5675);
FORCEADD Q_RES..2
(-3300 5800);
FORCEPROP 1 LAST LOCATION R17
J 0
(-3275 5925);
DISPLAY 0.489362 (-3275 5925);
PAINT SKYBLUE (-3275 5925);
FORCEPROP 0 LAST $SEC 1
J 0
(-3250 5975);
DISPLAY 0.680851 (-3250 5975);
PAINT MONO (-3250 5975);
DISPLAY INVISIBLE (-3250 5975);
FORCEPROP 0 LAST CDS_SEC 1
J 0
(-3250 5975);
DISPLAY 1.021277 (-3250 5975);
DISPLAY INVISIBLE (-3250 5975);
FORCEPROP 1 LASTPIN (-3300 5900) $PN 1
J 0
(-3295 5862);
DISPLAY 0.489362 (-3295 5862);
PAINT MONO (-3295 5862);
FORCEPROP 1 LASTPIN (-3300 5700) $PN 2
J 0
(-3295 5710);
DISPLAY 0.489362 (-3295 5710);
PAINT MONO (-3295 5710);
FORCEPROP 1 LAST TOLERANCE 1%
J 0
(-3255 5825);
DISPLAY 0.489362 (-3255 5825);
PAINT SKYBLUE (-3255 5825);
FORCEPROP 1 LAST VALUE 10K
J 0
(-3255 5875);
DISPLAY 0.489362 (-3255 5875);
PAINT SKYBLUE (-3255 5875);
FORCEPROP 1 LAST PACK_TYPE 0402LF
J 0
(-3250 5675);
DISPLAY 0.489362 (-3250 5675);
PAINT SKYBLUE (-3250 5675);
FORCEPROP 1 LAST MATERIAL CHIP
J 0
(-3260 5725);
DISPLAY 0.489362 (-3260 5725);
PAINT SKYBLUE (-3260 5725);
FORCEPROP 1 LAST WATTAGE 1/16W
J 0
(-3260 5775);
DISPLAY 0.489362 (-3260 5775);
PAINT SKYBLUE (-3260 5775);
FORCEPROP 2 LAST BOM_COST MEM
J 0
(-3250 5975);
DISPLAY 0.808511 (-3250 5975);
DISPLAY INVISIBLE (-3250 5975);
FORCEPROP 2 LAST CDS_LIB pure_quanta
J 0
(-3300 5800);
DISPLAY INVISIBLE (-3300 5800);
FORCEPROP 1 LAST PATH I125
J 0
(-3250 5975);
DISPLAY 0.978723 (-3250 5975);
PAINT WHITE (-3250 5975);
DISPLAY INVISIBLE (-3250 5975);
FORCEPROP 1 LAST PART_NUMBER CS31002FB08
J 0
(-3260 5675);
DISPLAY 0.489362 (-3260 5675);
PAINT SKYBLUE (-3260 5675);
DISPLAY INVISIBLE (-3260 5675);
FORCEADD Q_RES..2
(-3100 5800);
FORCEPROP 1 LAST LOCATION R18
J 0
(-3075 5925);
DISPLAY 0.489362 (-3075 5925);
PAINT SKYBLUE (-3075 5925);
FORCEPROP 0 LAST $SEC 1
J 0
(-3050 5975);
DISPLAY 0.680851 (-3050 5975);
PAINT MONO (-3050 5975);
DISPLAY INVISIBLE (-3050 5975);
FORCEPROP 0 LAST CDS_SEC 1
J 0
(-3050 5975);
DISPLAY 1.021277 (-3050 5975);
DISPLAY INVISIBLE (-3050 5975);
FORCEPROP 1 LASTPIN (-3100 5900) $PN 1
J 0
(-3095 5862);
DISPLAY 0.489362 (-3095 5862);
PAINT MONO (-3095 5862);
FORCEPROP 1 LASTPIN (-3100 5700) $PN 2
J 0
(-3095 5710);
DISPLAY 0.489362 (-3095 5710);
PAINT MONO (-3095 5710);
FORCEPROP 1 LAST MATERIAL CHIP
J 0
(-3060 5725);
DISPLAY 0.489362 (-3060 5725);
PAINT SKYBLUE (-3060 5725);
FORCEPROP 1 LAST TOLERANCE 1%
J 0
(-3055 5825);
DISPLAY 0.489362 (-3055 5825);
PAINT SKYBLUE (-3055 5825);
FORCEPROP 1 LAST VALUE 10K
J 0
(-3055 5875);
DISPLAY 0.489362 (-3055 5875);
PAINT SKYBLUE (-3055 5875);
FORCEPROP 1 LAST PACK_TYPE 0402LF
J 0
(-3050 5675);
DISPLAY 0.489362 (-3050 5675);
PAINT SKYBLUE (-3050 5675);
FORCEPROP 1 LAST WATTAGE 1/16W
J 0
(-3060 5775);
DISPLAY 0.489362 (-3060 5775);
PAINT SKYBLUE (-3060 5775);
FORCEPROP 2 LAST BOM_COST MEM
J 0
(-3050 5975);
DISPLAY 0.808511 (-3050 5975);
DISPLAY INVISIBLE (-3050 5975);
FORCEPROP 2 LAST CDS_LIB pure_quanta
J 0
(-3100 5800);
DISPLAY INVISIBLE (-3100 5800);
FORCEPROP 1 LAST PATH I126
J 0
(-3050 5975);
DISPLAY 0.978723 (-3050 5975);
PAINT WHITE (-3050 5975);
DISPLAY INVISIBLE (-3050 5975);
FORCEPROP 1 LAST PART_NUMBER CS31002FB08
J 0
(-3060 5675);
DISPLAY 0.489362 (-3060 5675);
PAINT SKYBLUE (-3060 5675);
DISPLAY INVISIBLE (-3060 5675);
FORCEADD GND..1
(-2875 5575);
FORCEPROP 3 LASTPIN (-2875 5625) SIG_NAME GND\g
J 0
(-2865 5635);
DISPLAY 0.659574 (-2865 5635);
PAINT MONO (-2865 5635);
DISPLAY INVISIBLE (-2865 5635);
FORCEPROP 1 LAST VOLTAGE 0.0
J 0
(-2920 5532);
DISPLAY 0.723404 (-2920 5532);
PAINT SKYBLUE (-2920 5532);
DISPLAY INVISIBLE (-2920 5532);
FORCEPROP 2 LAST CDS_LIB mstr_symbols
J 0
(-2875 5575);
DISPLAY INVISIBLE (-2875 5575);
FORCEPROP 1 LAST SIZE 1B
J 0
(-2800 5525);
DISPLAY 0.851064 (-2800 5525);
PAINT GREEN (-2800 5525);
DISPLAY INVISIBLE (-2800 5525);
FORCEPROP 2 LAST BOM_COST MEM
J 0
(-2975 5650);
DISPLAY 0.808511 (-2975 5650);
DISPLAY INVISIBLE (-2975 5650);
FORCEPROP 1 LAST BODY_TYPE PLUMBING
J 0
(-2920 5532);
DISPLAY 0.340426 (-2920 5532);
PAINT GREEN (-2920 5532);
DISPLAY INVISIBLE (-2920 5532);
FORCEPROP 1 LAST HDL_POWER GND
J 0
(-2875 5725);
DISPLAY 0.851064 (-2875 5725);
PAINT GREEN (-2875 5725);
DISPLAY INVISIBLE (-2875 5725);
FORCEPROP 1 LAST PATH I127
J 0
(-2800 5575);
DISPLAY 0.872340 (-2800 5575);
PAINT AQUA (-2800 5575);
DISPLAY INVISIBLE (-2800 5575);
FORCEADD Q_RES..2
(-2875 5800);
FORCEPROP 1 LAST LOCATION R19
J 0
(-2850 5925);
DISPLAY 0.489362 (-2850 5925);
PAINT SKYBLUE (-2850 5925);
FORCEPROP 0 LAST $SEC 1
J 0
(-2825 5975);
DISPLAY 0.680851 (-2825 5975);
PAINT MONO (-2825 5975);
DISPLAY INVISIBLE (-2825 5975);
FORCEPROP 0 LAST CDS_SEC 1
J 0
(-2825 5975);
DISPLAY 1.021277 (-2825 5975);
DISPLAY INVISIBLE (-2825 5975);
FORCEPROP 1 LASTPIN (-2875 5900) $PN 1
J 0
(-2870 5862);
DISPLAY 0.489362 (-2870 5862);
PAINT MONO (-2870 5862);
FORCEPROP 1 LASTPIN (-2875 5700) $PN 2
J 0
(-2870 5710);
DISPLAY 0.489362 (-2870 5710);
PAINT MONO (-2870 5710);
FORCEPROP 1 LAST MATERIAL CHIP
J 0
(-2835 5725);
DISPLAY 0.489362 (-2835 5725);
PAINT SKYBLUE (-2835 5725);
FORCEPROP 1 LAST TOLERANCE 1%
J 0
(-2830 5825);
DISPLAY 0.489362 (-2830 5825);
PAINT SKYBLUE (-2830 5825);
FORCEPROP 1 LAST VALUE 10K
J 0
(-2830 5875);
DISPLAY 0.489362 (-2830 5875);
PAINT SKYBLUE (-2830 5875);
FORCEPROP 1 LAST PACK_TYPE 0402LF
J 0
(-2825 5675);
DISPLAY 0.489362 (-2825 5675);
PAINT SKYBLUE (-2825 5675);
FORCEPROP 1 LAST WATTAGE 1/16W
J 0
(-2835 5775);
DISPLAY 0.489362 (-2835 5775);
PAINT SKYBLUE (-2835 5775);
FORCEPROP 2 LAST CDS_LIB pure_quanta
J 0
(-2875 5800);
DISPLAY INVISIBLE (-2875 5800);
FORCEPROP 2 LAST BOM_COST MEM
J 0
(-2825 5975);
DISPLAY 0.808511 (-2825 5975);
DISPLAY INVISIBLE (-2825 5975);
FORCEPROP 1 LAST PATH I128
J 0
(-2825 5975);
DISPLAY 0.978723 (-2825 5975);
PAINT WHITE (-2825 5975);
DISPLAY INVISIBLE (-2825 5975);
FORCEPROP 1 LAST PART_NUMBER CS31002FB08
J 0
(-2835 5675);
DISPLAY 0.489362 (-2835 5675);
PAINT SKYBLUE (-2835 5675);
DISPLAY INVISIBLE (-2835 5675);
FORCEADD OFFPAGE..1
R 2
(-2025 6075);
FORCEPROP 2 LAST $XR1 81 
J 0
(-1749 6075);
DISPLAY 0.638298 (-1749 6075);
PAINT MONO (-1749 6075);
FORCEPROP 2 LAST $XR0 55 
J 0
(-1839 6075);
DISPLAY 0.638298 (-1839 6075);
PAINT MONO (-1839 6075);
FORCEPROP 2 LAST CDS_LIB standard
J 0
(-2025 6075);
DISPLAY INVISIBLE (-2025 6075);
FORCEPROP 1 LAST OFFPAGE TRUE
J 2
(-2350 5950);
DISPLAY 0.872340 (-2350 5950);
PAINT GREEN (-2350 5950);
DISPLAY INVISIBLE (-2350 5950);
FORCEPROP 1 LAST COMMENT_BODY TRUE
J 2
(-2150 5975);
DISPLAY 0.872340 (-2150 5975);
PAINT GREEN (-2150 5975);
DISPLAY INVISIBLE (-2150 5975);
FORCEPROP 2 LAST PATH I129
J 0
(-1725 6125);
DISPLAY 0.680851 (-1725 6125);
DISPLAY INVISIBLE (-1725 6125);
FORCEADD OFFPAGE..5
(-8225 4325);
FORCEPROP 2 LAST $XR2 139 
J 0
(-8689 4325);
DISPLAY 0.638298 (-8689 4325);
PAINT MONO (-8689 4325);
FORCEPROP 2 LAST $XR1 133 
J 0
(-8569 4325);
DISPLAY 0.638298 (-8569 4325);
PAINT MONO (-8569 4325);
FORCEPROP 2 LAST $XR0 80 
J 0
(-8449 4325);
DISPLAY 0.638298 (-8449 4325);
PAINT MONO (-8449 4325);
FORCEPROP 2 LAST CDS_LIB standard
J 0
(-8225 4325);
DISPLAY INVISIBLE (-8225 4325);
FORCEPROP 1 LAST OFFPAGE TRUE
J 0
(-7900 4200);
DISPLAY 0.872340 (-7900 4200);
PAINT GREEN (-7900 4200);
DISPLAY INVISIBLE (-7900 4200);
FORCEPROP 1 LAST COMMENT_BODY TRUE
J 0
(-8125 4250);
DISPLAY 0.872340 (-8125 4250);
PAINT GREEN (-8125 4250);
DISPLAY INVISIBLE (-8125 4250);
FORCEPROP 2 LAST PATH I13
J 0
(-8475 4375);
DISPLAY 0.680851 (-8475 4375);
DISPLAY INVISIBLE (-8475 4375);
FORCEADD OFFPAGE..1
R 2
(-2025 6125);
FORCEPROP 2 LAST $XR1 81 
J 0
(-1749 6125);
DISPLAY 0.638298 (-1749 6125);
PAINT MONO (-1749 6125);
FORCEPROP 2 LAST $XR0 55 
J 0
(-1839 6125);
DISPLAY 0.638298 (-1839 6125);
PAINT MONO (-1839 6125);
FORCEPROP 2 LAST CDS_LIB standard
J 0
(-2025 6125);
DISPLAY INVISIBLE (-2025 6125);
FORCEPROP 1 LAST OFFPAGE TRUE
J 2
(-2350 6000);
DISPLAY 0.872340 (-2350 6000);
PAINT GREEN (-2350 6000);
DISPLAY INVISIBLE (-2350 6000);
FORCEPROP 1 LAST COMMENT_BODY TRUE
J 2
(-2150 6025);
DISPLAY 0.872340 (-2150 6025);
PAINT GREEN (-2150 6025);
DISPLAY INVISIBLE (-2150 6025);
FORCEPROP 2 LAST PATH I130
J 0
(-1725 6175);
DISPLAY 0.680851 (-1725 6175);
DISPLAY INVISIBLE (-1725 6175);
FORCEADD OFFPAGE..1
R 2
(-2025 6175);
FORCEPROP 2 LAST $XR1 81 
J 0
(-1749 6175);
DISPLAY 0.638298 (-1749 6175);
PAINT MONO (-1749 6175);
FORCEPROP 2 LAST $XR0 28 
J 0
(-1839 6175);
DISPLAY 0.638298 (-1839 6175);
PAINT MONO (-1839 6175);
FORCEPROP 2 LAST CDS_LIB standard
J 0
(-2025 6175);
DISPLAY INVISIBLE (-2025 6175);
FORCEPROP 1 LAST OFFPAGE TRUE
J 2
(-2350 6050);
DISPLAY 0.872340 (-2350 6050);
PAINT GREEN (-2350 6050);
DISPLAY INVISIBLE (-2350 6050);
FORCEPROP 1 LAST COMMENT_BODY TRUE
J 2
(-2150 6075);
DISPLAY 0.872340 (-2150 6075);
PAINT GREEN (-2150 6075);
DISPLAY INVISIBLE (-2150 6075);
FORCEPROP 2 LAST PATH I131
J 0
(-1725 6225);
DISPLAY 0.680851 (-1725 6225);
DISPLAY INVISIBLE (-1725 6225);
FORCEADD OFFPAGE..1
R 2
(-2025 6225);
FORCEPROP 2 LAST $XR1 81 
J 0
(-1749 6225);
DISPLAY 0.638298 (-1749 6225);
PAINT MONO (-1749 6225);
FORCEPROP 2 LAST $XR0 28 
J 0
(-1839 6225);
DISPLAY 0.638298 (-1839 6225);
PAINT MONO (-1839 6225);
FORCEPROP 2 LAST CDS_LIB standard
J 0
(-2025 6225);
DISPLAY INVISIBLE (-2025 6225);
FORCEPROP 1 LAST OFFPAGE TRUE
J 2
(-2350 6100);
DISPLAY 0.872340 (-2350 6100);
PAINT GREEN (-2350 6100);
DISPLAY INVISIBLE (-2350 6100);
FORCEPROP 1 LAST COMMENT_BODY TRUE
J 2
(-2150 6125);
DISPLAY 0.872340 (-2150 6125);
PAINT GREEN (-2150 6125);
DISPLAY INVISIBLE (-2150 6125);
FORCEPROP 2 LAST PATH I132
J 0
(-1725 6275);
DISPLAY 0.680851 (-1725 6275);
DISPLAY INVISIBLE (-1725 6275);
FORCEADD OFFPAGE..2
(-1400 5125);
FORCEPROP 2 LAST $XR1 144 
J 0
(-1121 5125);
DISPLAY 0.638298 (-1121 5125);
PAINT MONO (-1121 5125);
FORCEPROP 2 LAST $XR0 81 
J 0
(-1211 5125);
DISPLAY 0.638298 (-1211 5125);
PAINT MONO (-1211 5125);
FORCEPROP 2 LAST CDS_LIB standard
J 0
(-1400 5125);
DISPLAY INVISIBLE (-1400 5125);
FORCEPROP 1 LAST OFFPAGE TRUE
J 0
(-1075 5000);
DISPLAY 0.872340 (-1075 5000);
PAINT GREEN (-1075 5000);
DISPLAY INVISIBLE (-1075 5000);
FORCEPROP 1 LAST COMMENT_BODY TRUE
J 0
(-1445 5030);
DISPLAY 0.872340 (-1445 5030);
PAINT GREEN (-1445 5030);
DISPLAY INVISIBLE (-1445 5030);
FORCEPROP 2 LAST PATH I133
J 0
(-1100 5175);
DISPLAY 0.680851 (-1100 5175);
DISPLAY INVISIBLE (-1100 5175);
FORCEADD OFFPAGE..2
(-1400 5200);
FORCEPROP 2 LAST $XR1 145 
J 0
(-1121 5200);
DISPLAY 0.638298 (-1121 5200);
PAINT MONO (-1121 5200);
FORCEPROP 2 LAST $XR0 81 
J 0
(-1211 5200);
DISPLAY 0.638298 (-1211 5200);
PAINT MONO (-1211 5200);
FORCEPROP 2 LAST CDS_LIB standard
J 0
(-1400 5200);
DISPLAY INVISIBLE (-1400 5200);
FORCEPROP 1 LAST OFFPAGE TRUE
J 0
(-1075 5075);
DISPLAY 0.872340 (-1075 5075);
PAINT GREEN (-1075 5075);
DISPLAY INVISIBLE (-1075 5075);
FORCEPROP 1 LAST COMMENT_BODY TRUE
J 0
(-1445 5105);
DISPLAY 0.872340 (-1445 5105);
PAINT GREEN (-1445 5105);
DISPLAY INVISIBLE (-1445 5105);
FORCEPROP 2 LAST PATH I134
J 0
(-1100 5250);
DISPLAY 0.680851 (-1100 5250);
DISPLAY INVISIBLE (-1100 5250);
FORCEADD Q_CAP..2
(-1200 825);
FORCEPROP 1 LAST LOCATION C359
J 0
(-1500 825);
DISPLAY 0.489362 (-1500 825);
PAINT SKYBLUE (-1500 825);
FORCEPROP 2 LAST $SEC 1
J 0
(-1200 1075);
DISPLAY 0.680851 (-1200 1075);
PAINT MONO (-1200 1075);
DISPLAY INVISIBLE (-1200 1075);
FORCEPROP 2 LAST CDS_SEC 1
J 0
(-1200 1075);
DISPLAY 1.021277 (-1200 1075);
DISPLAY INVISIBLE (-1200 1075);
FORCEPROP 1 LASTPIN (-1300 825) $PN 1
J 0
(-1310 840);
DISPLAY 0.489362 (-1310 840);
PAINT MONO (-1310 840);
FORCEPROP 1 LASTPIN (-1100 825) $PN 2
J 0
(-1115 840);
DISPLAY 0.489362 (-1115 840);
PAINT MONO (-1115 840);
FORCEPROP 1 LAST VALUE 0.1UF
J 2
(-825 825);
DISPLAY 0.489362 (-825 825);
PAINT SKYBLUE (-825 825);
FORCEPROP 1 LAST PACK_TYPE C0402
J 1
(-350 775);
DISPLAY 0.978723 (-350 775);
PAINT SKYBLUE (-350 775);
DISPLAY INVISIBLE (-350 775);
FORCEPROP 1 LAST VOLTAGE 16V
J 0
(-675 775);
DISPLAY 0.978723 (-675 775);
PAINT SKYBLUE (-675 775);
DISPLAY INVISIBLE (-675 775);
FORCEPROP 1 LAST TOLERANCE 10%
J 2
(-925 775);
DISPLAY 0.978723 (-925 775);
PAINT SKYBLUE (-925 775);
DISPLAY INVISIBLE (-925 775);
FORCEPROP 1 LAST MATERIAL X7R
J 0
(-850 775);
DISPLAY 0.978723 (-850 775);
PAINT SKYBLUE (-850 775);
DISPLAY INVISIBLE (-850 775);
FORCEPROP 2 LAST CDS_LIB pure_quanta
J 0
(-1200 825);
DISPLAY INVISIBLE (-1200 825);
FORCEPROP 1 LAST PATH I135
J 0
(-1200 1025);
DISPLAY 0.978723 (-1200 1025);
PAINT WHITE (-1200 1025);
DISPLAY INVISIBLE (-1200 1025);
FORCEPROP 1 LAST PART_NUMBER CH4103K1B08
J 1
(-450 825);
DISPLAY 0.978723 (-450 825);
PAINT SKYBLUE (-450 825);
DISPLAY INVISIBLE (-450 825);
FORCEADD Q_RES..1
(-5350 5075);
FORCEPROP 1 LAST LOCATION R6114
J 0
(-5550 5075);
DISPLAY 0.510638 (-5550 5075);
FORCEPROP 0 LAST $SEC 1
J 0
(-4975 5175);
DISPLAY 0.680851 (-4975 5175);
PAINT MONO (-4975 5175);
DISPLAY INVISIBLE (-4975 5175);
FORCEPROP 0 LAST CDS_SEC 1
J 0
(-4975 5175);
DISPLAY 0.680851 (-4975 5175);
DISPLAY INVISIBLE (-4975 5175);
FORCEPROP 1 LASTPIN (-5450 5075) $PN 1
J 0
(-5438 5087);
DISPLAY 0.787234 (-5438 5087);
PAINT MONO (-5438 5087);
FORCEPROP 1 LASTPIN (-5250 5075) $PN 2
J 0
(-5288 5087);
DISPLAY 0.787234 (-5288 5087);
PAINT MONO (-5288 5087);
FORCEPROP 1 LAST WATTAGE 1/16W
J 0
(-4700 5125);
DISPLAY 0.510638 (-4700 5125);
FORCEPROP 1 LAST VALUE 2K
J 2
(-5200 5075);
DISPLAY 0.510638 (-5200 5075);
FORCEPROP 1 LAST MATERIAL CHIP
J 0
(-5150 5075);
DISPLAY 0.638298 (-5150 5075);
FORCEPROP 1 LAST PACK_TYPE 0402LF
J 0
(-4875 5125);
DISPLAY 0.510638 (-4875 5125);
FORCEPROP 1 LAST TOLERANCE 1%
J 0
(-4975 5125);
DISPLAY 0.510638 (-4975 5125);
FORCEPROP 2 LAST CDS_LIB pure_quanta
J 0
(-5350 5075);
DISPLAY INVISIBLE (-5350 5075);
FORCEPROP 1 LAST PATH I137
J 0
(-5400 5225);
DISPLAY 0.978723 (-5400 5225);
PAINT WHITE (-5400 5225);
DISPLAY INVISIBLE (-5400 5225);
FORCEPROP 1 LAST PART_NUMBER CS22002FB07
J 0
(-4975 5150);
DISPLAY 0.510638 (-4975 5150);
DISPLAY INVISIBLE (-4975 5150);
FORCEADD OFFPAGE..1
(-6100 5075);
FORCEPROP 2 LAST $XR1 85 
J 0
(-6441 5075);
DISPLAY 0.638298 (-6441 5075);
PAINT MONO (-6441 5075);
FORCEPROP 2 LAST $XR0 81 
J 0
(-6351 5075);
DISPLAY 0.638298 (-6351 5075);
PAINT MONO (-6351 5075);
FORCEPROP 2 LAST CDS_LIB standard
J 0
(-6100 5075);
DISPLAY INVISIBLE (-6100 5075);
FORCEPROP 1 LAST OFFPAGE TRUE
J 0
(-5770 4945);
PAINT GREEN (-5770 4945);
DISPLAY INVISIBLE (-5770 4945);
FORCEPROP 1 LAST COMMENT_BODY TRUE
J 0
(-5970 4975);
DISPLAY 1.106383 (-5970 4975);
PAINT PEACH (-5970 4975);
DISPLAY INVISIBLE (-5970 4975);
FORCEPROP 2 LAST PATH I139
J 0
(-6050 5150);
DISPLAY 0.680851 (-6050 5150);
DISPLAY INVISIBLE (-6050 5150);
FORCEADD OFFPAGE..5
(-8200 4575);
FORCEPROP 2 LAST $XR2 82 
J 0
(-8665 4575);
DISPLAY 0.638298 (-8665 4575);
PAINT MONO (-8665 4575);
FORCEPROP 2 LAST $XR1 80 
J 0
(-8575 4575);
DISPLAY 0.638298 (-8575 4575);
PAINT MONO (-8575 4575);
FORCEPROP 2 LAST $XR0 145 
J 0
(-8485 4575);
DISPLAY 0.638298 (-8485 4575);
PAINT MONO (-8485 4575);
FORCEPROP 2 LAST CDS_LIB standard
J 0
(-8200 4575);
DISPLAY INVISIBLE (-8200 4575);
FORCEPROP 1 LAST OFFPAGE TRUE
J 0
(-7875 4450);
DISPLAY 0.872340 (-7875 4450);
PAINT GREEN (-7875 4450);
DISPLAY INVISIBLE (-7875 4450);
FORCEPROP 1 LAST COMMENT_BODY TRUE
J 0
(-8100 4500);
DISPLAY 0.872340 (-8100 4500);
PAINT GREEN (-8100 4500);
DISPLAY INVISIBLE (-8100 4500);
FORCEPROP 2 LAST PATH I14
J 0
(-8475 4625);
DISPLAY 0.680851 (-8475 4625);
DISPLAY INVISIBLE (-8475 4625);
FORCEADD UNIVERSAL_GND..1
(-4650 4775);
FORCEPROP 3 LASTPIN (-4650 4825) SIG_NAME GND\g
J 0
(-4640 4835);
DISPLAY 0.659574 (-4640 4835);
PAINT MONO (-4640 4835);
DISPLAY INVISIBLE (-4640 4835);
FORCEPROP 2 LAST CDS_LIB pure_quanta_power
J 0
(-4650 4775);
DISPLAY INVISIBLE (-4650 4775);
FORCEPROP 1 LAST HDL_POWER GND
J 1
(-4625 4700);
DISPLAY 0.872340 (-4625 4700);
PAINT GREEN (-4625 4700);
DISPLAY INVISIBLE (-4625 4700);
FORCEPROP 1 LAST PATH I140
J 0
(-4575 4775);
DISPLAY 0.872340 (-4575 4775);
PAINT AQUA (-4575 4775);
DISPLAY INVISIBLE (-4575 4775);
FORCEADD Q_RES..1
(-5350 5025);
FORCEPROP 1 LAST LOCATION R6115
J 0
(-5550 5025);
DISPLAY 0.510638 (-5550 5025);
FORCEPROP 0 LAST $SEC 1
J 0
(-4975 5125);
DISPLAY 0.680851 (-4975 5125);
PAINT MONO (-4975 5125);
DISPLAY INVISIBLE (-4975 5125);
FORCEPROP 0 LAST CDS_SEC 1
J 0
(-4975 5125);
DISPLAY 0.680851 (-4975 5125);
DISPLAY INVISIBLE (-4975 5125);
FORCEPROP 1 LASTPIN (-5450 5025) $PN 1
J 0
(-5438 5037);
DISPLAY 0.787234 (-5438 5037);
PAINT MONO (-5438 5037);
FORCEPROP 1 LASTPIN (-5250 5025) $PN 2
J 0
(-5288 5037);
DISPLAY 0.787234 (-5288 5037);
PAINT MONO (-5288 5037);
FORCEPROP 1 LAST MATERIAL CHIP
J 0
(-5150 5025);
DISPLAY 0.638298 (-5150 5025);
FORCEPROP 1 LAST VALUE 2K
J 2
(-5200 5025);
DISPLAY 0.510638 (-5200 5025);
FORCEPROP 1 LAST PACK_TYPE 0402LF
J 0
(-4875 5075);
DISPLAY 0.510638 (-4875 5075);
DISPLAY INVISIBLE (-4875 5075);
FORCEPROP 1 LAST WATTAGE 1/16W
J 0
(-4700 5075);
DISPLAY 0.510638 (-4700 5075);
DISPLAY INVISIBLE (-4700 5075);
FORCEPROP 1 LAST TOLERANCE 1%
J 0
(-4975 5075);
DISPLAY 0.510638 (-4975 5075);
DISPLAY INVISIBLE (-4975 5075);
FORCEPROP 2 LAST CDS_LIB pure_quanta
J 0
(-5350 5025);
DISPLAY INVISIBLE (-5350 5025);
FORCEPROP 1 LAST PATH I141
J 0
(-5400 5175);
DISPLAY 0.978723 (-5400 5175);
PAINT WHITE (-5400 5175);
DISPLAY INVISIBLE (-5400 5175);
FORCEPROP 1 LAST PART_NUMBER CS22002FB07
J 0
(-4975 5100);
DISPLAY 0.510638 (-4975 5100);
DISPLAY INVISIBLE (-4975 5100);
FORCEADD OFFPAGE..1
(-6100 5025);
FORCEPROP 2 LAST $XR1 85 
J 0
(-6441 5025);
DISPLAY 0.638298 (-6441 5025);
PAINT MONO (-6441 5025);
FORCEPROP 2 LAST $XR0 81 
J 0
(-6351 5025);
DISPLAY 0.638298 (-6351 5025);
PAINT MONO (-6351 5025);
FORCEPROP 2 LAST CDS_LIB standard
J 0
(-6100 5025);
DISPLAY INVISIBLE (-6100 5025);
FORCEPROP 1 LAST OFFPAGE TRUE
J 0
(-5770 4895);
PAINT GREEN (-5770 4895);
DISPLAY INVISIBLE (-5770 4895);
FORCEPROP 1 LAST COMMENT_BODY TRUE
J 0
(-5970 4925);
DISPLAY 1.106383 (-5970 4925);
PAINT PEACH (-5970 4925);
DISPLAY INVISIBLE (-5970 4925);
FORCEPROP 2 LAST PATH I142
J 0
(-6300 5075);
DISPLAY 0.680851 (-6300 5075);
DISPLAY INVISIBLE (-6300 5075);
FORCEADD Q_RES..2
(-2875 3250);
FORCEPROP 1 LAST LOCATION R6185
J 0
(-2850 3375);
DISPLAY 0.489362 (-2850 3375);
PAINT SKYBLUE (-2850 3375);
FORCEPROP 0 LAST $SEC 1
J 0
(-2850 3400);
DISPLAY 0.680851 (-2850 3400);
PAINT MONO (-2850 3400);
DISPLAY INVISIBLE (-2850 3400);
FORCEPROP 0 LAST CDS_SEC 1
J 0
(-2850 3400);
DISPLAY 0.680851 (-2850 3400);
DISPLAY INVISIBLE (-2850 3400);
FORCEPROP 1 LASTPIN (-2875 3350) $PN 1
J 0
(-2870 3312);
DISPLAY 0.787234 (-2870 3312);
PAINT MONO (-2870 3312);
FORCEPROP 1 LASTPIN (-2875 3150) $PN 2
J 0
(-2870 3160);
DISPLAY 0.787234 (-2870 3160);
PAINT MONO (-2870 3160);
FORCEPROP 1 LAST TOLERANCE 1%
J 0
(-2830 3275);
DISPLAY 0.489362 (-2830 3275);
PAINT SKYBLUE (-2830 3275);
FORCEPROP 1 LAST VALUE 10K
J 0
(-2830 3325);
DISPLAY 0.489362 (-2830 3325);
PAINT SKYBLUE (-2830 3325);
FORCEPROP 1 LAST WATTAGE 1/16W
J 0
(-2835 3225);
DISPLAY 0.489362 (-2835 3225);
PAINT SKYBLUE (-2835 3225);
FORCEPROP 1 LAST MATERIAL CHIP
J 0
(-2835 3175);
DISPLAY 0.489362 (-2835 3175);
PAINT SKYBLUE (-2835 3175);
FORCEPROP 1 LAST PACK_TYPE 0402LF
J 0
(-2825 3125);
DISPLAY 0.489362 (-2825 3125);
PAINT SKYBLUE (-2825 3125);
FORCEPROP 2 LAST BOM_COST MEM
J 0
(-2825 3425);
DISPLAY 0.808511 (-2825 3425);
DISPLAY INVISIBLE (-2825 3425);
FORCEPROP 2 LAST CDS_LIB pure_quanta
J 0
(-2875 3250);
DISPLAY INVISIBLE (-2875 3250);
FORCEPROP 1 LAST PATH I143
J 0
(-2825 3425);
DISPLAY 0.978723 (-2825 3425);
PAINT WHITE (-2825 3425);
DISPLAY INVISIBLE (-2825 3425);
FORCEPROP 1 LAST PART_NUMBER CS31002FB08
J 0
(-2835 3125);
DISPLAY 0.489362 (-2835 3125);
PAINT SKYBLUE (-2835 3125);
DISPLAY INVISIBLE (-2835 3125);
FORCEADD GND..1
(-2875 3000);
FORCEPROP 3 LASTPIN (-2875 3050) SIG_NAME GND\g
J 0
(-2865 3060);
DISPLAY 0.659574 (-2865 3060);
PAINT MONO (-2865 3060);
DISPLAY INVISIBLE (-2865 3060);
FORCEPROP 2 LAST CDS_LIB pure_quanta_power
J 0
(-2875 3000);
DISPLAY INVISIBLE (-2875 3000);
FORCEPROP 2 LAST BOM_COST MEM
J 0
(-2975 3075);
DISPLAY 0.808511 (-2975 3075);
DISPLAY INVISIBLE (-2975 3075);
FORCEPROP 1 LAST SIZE 1B
J 0
(-2800 2950);
DISPLAY 0.851064 (-2800 2950);
PAINT GREEN (-2800 2950);
DISPLAY INVISIBLE (-2800 2950);
FORCEPROP 1 LAST HDL_POWER GND
J 0
(-2875 3150);
DISPLAY 0.851064 (-2875 3150);
PAINT GREEN (-2875 3150);
DISPLAY INVISIBLE (-2875 3150);
FORCEPROP 1 LAST PATH I144
J 0
(-2800 3000);
DISPLAY 0.872340 (-2800 3000);
PAINT AQUA (-2800 3000);
DISPLAY INVISIBLE (-2800 3000);
FORCEADD OFFPAGE..1
R 2
(-2225 3450);
FORCEPROP 2 LAST $XR2 161 
J 0
(-1859 3450);
DISPLAY 0.638298 (-1859 3450);
PAINT MONO (-1859 3450);
FORCEPROP 2 LAST $XR1 83 
J 0
(-1949 3450);
DISPLAY 0.638298 (-1949 3450);
PAINT MONO (-1949 3450);
FORCEPROP 2 LAST $XR0 82 
J 0
(-2039 3450);
DISPLAY 0.638298 (-2039 3450);
PAINT MONO (-2039 3450);
FORCEPROP 2 LAST CDS_LIB standard
J 0
(-2225 3450);
DISPLAY INVISIBLE (-2225 3450);
FORCEPROP 1 LAST OFFPAGE TRUE
J 2
(-2550 3325);
DISPLAY 0.872340 (-2550 3325);
PAINT GREEN (-2550 3325);
DISPLAY INVISIBLE (-2550 3325);
FORCEPROP 1 LAST COMMENT_BODY TRUE
J 2
(-2350 3350);
DISPLAY 0.872340 (-2350 3350);
PAINT GREEN (-2350 3350);
DISPLAY INVISIBLE (-2350 3350);
FORCEPROP 2 LAST PATH I145
J 0
(-2050 3525);
DISPLAY 0.680851 (-2050 3525);
DISPLAY INVISIBLE (-2050 3525);
FORCEADD Q_RES..1
(-7050 5175);
FORCEPROP 1 LAST LOCATION R6186
J 0
(-7350 5175);
DISPLAY 0.489362 (-7350 5175);
PAINT SKYBLUE (-7350 5175);
FORCEPROP 0 LAST $SEC 1
J 0
(-6925 5200);
DISPLAY 0.680851 (-6925 5200);
PAINT MONO (-6925 5200);
DISPLAY INVISIBLE (-6925 5200);
FORCEPROP 0 LAST CDS_SEC 1
J 0
(-6925 5200);
DISPLAY 0.680851 (-6925 5200);
DISPLAY INVISIBLE (-6925 5200);
FORCEPROP 1 LASTPIN (-7150 5175) $PN 1
J 0
(-7138 5187);
DISPLAY 0.787234 (-7138 5187);
PAINT MONO (-7138 5187);
FORCEPROP 1 LASTPIN (-6950 5175) $PN 2
J 0
(-6988 5187);
DISPLAY 0.787234 (-6988 5187);
PAINT MONO (-6988 5187);
FORCEPROP 1 LAST MATERIAL EMPTY
J 0
(-6950 5150);
DISPLAY 0.489362 (-6950 5150);
PAINT RED (-6950 5150);
FORCEPROP 1 LAST VALUE 4.7K
J 0
(-6925 5175);
DISPLAY 0.489362 (-6925 5175);
PAINT SKYBLUE (-6925 5175);
FORCEPROP 1 LAST WATTAGE 1/16W
J 2
(-7075 5025);
DISPLAY 0.510638 (-7075 5025);
PAINT SKYBLUE (-7075 5025);
DISPLAY INVISIBLE (-7075 5025);
FORCEPROP 1 LAST TOLERANCE 5%
J 0
(-6925 5175);
DISPLAY 0.510638 (-6925 5175);
PAINT SKYBLUE (-6925 5175);
DISPLAY INVISIBLE (-6925 5175);
FORCEPROP 1 LAST PACK_TYPE 0402LF
J 0
(-6800 5025);
DISPLAY 0.510638 (-6800 5025);
PAINT SKYBLUE (-6800 5025);
DISPLAY INVISIBLE (-6800 5025);
FORCEPROP 2 LAST CDS_LIB pure_quanta
J 0
(-7050 5175);
DISPLAY INVISIBLE (-7050 5175);
FORCEPROP 1 LAST PATH I146
J 0
(-7100 5325);
DISPLAY 0.978723 (-7100 5325);
PAINT WHITE (-7100 5325);
DISPLAY INVISIBLE (-7100 5325);
FORCEPROP 1 LAST PART_NUMBER CS24702JB10
J 0
(-7100 5275);
DISPLAY 0.510638 (-7100 5275);
PAINT SKYBLUE (-7100 5275);
DISPLAY INVISIBLE (-7100 5275);
FORCEADD OFFPAGE..5
(-8200 5175);
FORCEPROP 2 LAST $XR2 161 
J 0
(-8664 5175);
DISPLAY 0.638298 (-8664 5175);
PAINT MONO (-8664 5175);
FORCEPROP 2 LAST $XR1 83 
J 0
(-8544 5175);
DISPLAY 0.638298 (-8544 5175);
PAINT MONO (-8544 5175);
FORCEPROP 2 LAST $XR0 82 
J 0
(-8454 5175);
DISPLAY 0.638298 (-8454 5175);
PAINT MONO (-8454 5175);
FORCEPROP 2 LAST CDS_LIB standard
J 0
(-8200 5175);
DISPLAY INVISIBLE (-8200 5175);
FORCEPROP 1 LAST OFFPAGE TRUE
J 0
(-7875 5050);
DISPLAY 0.872340 (-7875 5050);
PAINT GREEN (-7875 5050);
DISPLAY INVISIBLE (-7875 5050);
FORCEPROP 1 LAST COMMENT_BODY TRUE
J 0
(-8100 5100);
DISPLAY 0.872340 (-8100 5100);
PAINT GREEN (-8100 5100);
DISPLAY INVISIBLE (-8100 5100);
FORCEPROP 2 LAST PATH I147
J 0
(-8150 5250);
DISPLAY 0.680851 (-8150 5250);
DISPLAY INVISIBLE (-8150 5250);
FORCEADD OFFPAGE..1
R 2
(-2225 3400);
FORCEPROP 2 LAST $XR2 161 
J 0
(-1859 3400);
DISPLAY 0.638298 (-1859 3400);
PAINT MONO (-1859 3400);
FORCEPROP 2 LAST $XR1 83 
J 0
(-1949 3400);
DISPLAY 0.638298 (-1949 3400);
PAINT MONO (-1949 3400);
FORCEPROP 2 LAST $XR0 82 
J 0
(-2039 3400);
DISPLAY 0.638298 (-2039 3400);
PAINT MONO (-2039 3400);
FORCEPROP 2 LAST CDS_LIB standard
J 0
(-2225 3400);
DISPLAY INVISIBLE (-2225 3400);
FORCEPROP 1 LAST OFFPAGE TRUE
J 2
(-2550 3275);
DISPLAY 0.872340 (-2550 3275);
PAINT GREEN (-2550 3275);
DISPLAY INVISIBLE (-2550 3275);
FORCEPROP 1 LAST COMMENT_BODY TRUE
J 2
(-2350 3300);
DISPLAY 0.872340 (-2350 3300);
PAINT GREEN (-2350 3300);
DISPLAY INVISIBLE (-2350 3300);
FORCEPROP 2 LAST PATH I148
J 0
(-2050 3475);
DISPLAY 0.680851 (-2050 3475);
DISPLAY INVISIBLE (-2050 3475);
FORCEADD OFFPAGE..5
(-8200 5375);
FORCEPROP 2 LAST $XR1 82 
J 0
(-8575 5375);
DISPLAY 0.638298 (-8575 5375);
PAINT MONO (-8575 5375);
FORCEPROP 2 LAST $XR0 207 
J 0
(-8485 5375);
DISPLAY 0.638298 (-8485 5375);
PAINT MONO (-8485 5375);
FORCEPROP 2 LAST CDS_LIB standard
J 0
(-8200 5375);
DISPLAY INVISIBLE (-8200 5375);
FORCEPROP 1 LAST OFFPAGE TRUE
J 0
(-7875 5250);
DISPLAY 0.872340 (-7875 5250);
PAINT GREEN (-7875 5250);
DISPLAY INVISIBLE (-7875 5250);
FORCEPROP 1 LAST COMMENT_BODY TRUE
J 0
(-8100 5300);
DISPLAY 0.872340 (-8100 5300);
PAINT GREEN (-8100 5300);
DISPLAY INVISIBLE (-8100 5300);
FORCEPROP 2 LAST PATH I15
J 0
(-8475 5425);
DISPLAY 0.680851 (-8475 5425);
DISPLAY INVISIBLE (-8475 5425);
FORCEADD GND..1
(-2675 2975);
FORCEPROP 3 LASTPIN (-2675 3025) SIG_NAME GND\g
J 0
(-2665 3035);
DISPLAY 0.659574 (-2665 3035);
PAINT MONO (-2665 3035);
DISPLAY INVISIBLE (-2665 3035);
FORCEPROP 2 LAST CDS_LIB pure_quanta_power
J 0
(-2675 2975);
DISPLAY INVISIBLE (-2675 2975);
FORCEPROP 2 LAST BOM_COST MEM
J 0
(-2775 3050);
DISPLAY 0.808511 (-2775 3050);
DISPLAY INVISIBLE (-2775 3050);
FORCEPROP 1 LAST SIZE 1B
J 0
(-2600 2925);
DISPLAY 0.851064 (-2600 2925);
PAINT GREEN (-2600 2925);
DISPLAY INVISIBLE (-2600 2925);
FORCEPROP 1 LAST HDL_POWER GND
J 0
(-2675 3125);
DISPLAY 0.851064 (-2675 3125);
PAINT GREEN (-2675 3125);
DISPLAY INVISIBLE (-2675 3125);
FORCEPROP 1 LAST PATH I150
J 0
(-2600 2975);
DISPLAY 0.872340 (-2600 2975);
PAINT AQUA (-2600 2975);
DISPLAY INVISIBLE (-2600 2975);
FORCEADD Q_RES..2
(-2675 3225);
FORCEPROP 1 LAST LOCATION R6187
J 0
(-2630 3350);
DISPLAY 0.510638 (-2630 3350);
FORCEPROP 0 LAST $SEC 1
J 0
(-2625 3375);
DISPLAY 0.680851 (-2625 3375);
PAINT MONO (-2625 3375);
DISPLAY INVISIBLE (-2625 3375);
FORCEPROP 0 LAST CDS_SEC 1
J 0
(-2625 3375);
DISPLAY 0.680851 (-2625 3375);
DISPLAY INVISIBLE (-2625 3375);
FORCEPROP 1 LASTPIN (-2675 3325) $PN 1
J 0
(-2670 3287);
DISPLAY 0.787234 (-2670 3287);
PAINT MONO (-2670 3287);
FORCEPROP 1 LASTPIN (-2675 3125) $PN 2
J 0
(-2670 3135);
DISPLAY 0.787234 (-2670 3135);
PAINT MONO (-2670 3135);
FORCEPROP 1 LAST PACK_TYPE 0402LF
J 0
(-2635 3050);
DISPLAY 0.510638 (-2635 3050);
FORCEPROP 1 LAST WATTAGE 1/16W
J 0
(-2635 3200);
DISPLAY 0.510638 (-2635 3200);
FORCEPROP 1 LAST MATERIAL EMPTY
J 0
(-2635 3150);
DISPLAY 0.510638 (-2635 3150);
FORCEPROP 1 LAST TOLERANCE 1%
J 0
(-2630 3250);
DISPLAY 0.510638 (-2630 3250);
FORCEPROP 1 LAST VALUE 10K
J 0
(-2630 3300);
DISPLAY 0.510638 (-2630 3300);
FORCEPROP 2 LAST CDS_LIB pure_quanta
J 0
(-2675 3225);
DISPLAY INVISIBLE (-2675 3225);
FORCEPROP 1 LAST PATH I151
J 0
(-2625 3400);
DISPLAY 0.978723 (-2625 3400);
PAINT WHITE (-2625 3400);
DISPLAY INVISIBLE (-2625 3400);
FORCEPROP 1 LAST PART_NUMBER CS31002FB08
J 0
(-2635 3100);
DISPLAY 0.510638 (-2635 3100);
DISPLAY INVISIBLE (-2635 3100);
FORCEADD Q_RES..1
(-7050 5125);
FORCEPROP 1 LAST LOCATION R6188
J 0
(-7350 5125);
DISPLAY 0.489362 (-7350 5125);
PAINT SKYBLUE (-7350 5125);
FORCEPROP 0 LAST $SEC 1
J 0
(-6925 5150);
DISPLAY 0.680851 (-6925 5150);
PAINT MONO (-6925 5150);
DISPLAY INVISIBLE (-6925 5150);
FORCEPROP 0 LAST CDS_SEC 1
J 0
(-6925 5150);
DISPLAY 0.680851 (-6925 5150);
DISPLAY INVISIBLE (-6925 5150);
FORCEPROP 1 LASTPIN (-7150 5125) $PN 1
J 0
(-7138 5137);
DISPLAY 0.787234 (-7138 5137);
PAINT MONO (-7138 5137);
FORCEPROP 1 LASTPIN (-6950 5125) $PN 2
J 0
(-6988 5137);
DISPLAY 0.787234 (-6988 5137);
PAINT MONO (-6988 5137);
FORCEPROP 1 LAST MATERIAL EMPTY
J 0
(-6950 5100);
DISPLAY 0.489362 (-6950 5100);
PAINT RED (-6950 5100);
FORCEPROP 1 LAST VALUE 4.7K
J 0
(-6925 5125);
DISPLAY 0.489362 (-6925 5125);
PAINT SKYBLUE (-6925 5125);
FORCEPROP 1 LAST PACK_TYPE 0402LF
J 0
(-6800 4975);
DISPLAY 0.510638 (-6800 4975);
PAINT SKYBLUE (-6800 4975);
DISPLAY INVISIBLE (-6800 4975);
FORCEPROP 1 LAST TOLERANCE 5%
J 0
(-6925 5125);
DISPLAY 0.510638 (-6925 5125);
PAINT SKYBLUE (-6925 5125);
DISPLAY INVISIBLE (-6925 5125);
FORCEPROP 1 LAST WATTAGE 1/16W
J 2
(-7075 4975);
DISPLAY 0.510638 (-7075 4975);
PAINT SKYBLUE (-7075 4975);
DISPLAY INVISIBLE (-7075 4975);
FORCEPROP 2 LAST CDS_LIB pure_quanta
J 0
(-7050 5125);
DISPLAY INVISIBLE (-7050 5125);
FORCEPROP 1 LAST PATH I152
J 0
(-7100 5275);
DISPLAY 0.978723 (-7100 5275);
PAINT WHITE (-7100 5275);
DISPLAY INVISIBLE (-7100 5275);
FORCEPROP 1 LAST PART_NUMBER CS24702JB10
J 0
(-7100 5225);
DISPLAY 0.510638 (-7100 5225);
PAINT SKYBLUE (-7100 5225);
DISPLAY INVISIBLE (-7100 5225);
FORCEADD OFFPAGE..5
(-8200 5125);
FORCEPROP 2 LAST $XR2 161 
J 0
(-8664 5125);
DISPLAY 0.638298 (-8664 5125);
PAINT MONO (-8664 5125);
FORCEPROP 2 LAST $XR1 83 
J 0
(-8544 5125);
DISPLAY 0.638298 (-8544 5125);
PAINT MONO (-8544 5125);
FORCEPROP 2 LAST $XR0 82 
J 0
(-8454 5125);
DISPLAY 0.638298 (-8454 5125);
PAINT MONO (-8454 5125);
FORCEPROP 2 LAST CDS_LIB standard
J 0
(-8200 5125);
DISPLAY INVISIBLE (-8200 5125);
FORCEPROP 1 LAST OFFPAGE TRUE
J 0
(-7875 5000);
DISPLAY 0.872340 (-7875 5000);
PAINT GREEN (-7875 5000);
DISPLAY INVISIBLE (-7875 5000);
FORCEPROP 1 LAST COMMENT_BODY TRUE
J 0
(-8100 5050);
DISPLAY 0.872340 (-8100 5050);
PAINT GREEN (-8100 5050);
DISPLAY INVISIBLE (-8100 5050);
FORCEPROP 2 LAST PATH I153
J 0
(-8150 5200);
DISPLAY 0.680851 (-8150 5200);
DISPLAY INVISIBLE (-8150 5200);
FORCEADD Q_RES..1
(-5350 4925);
FORCEPROP 1 LAST LOCATION R3
J 0
(-5550 4925);
DISPLAY 0.510638 (-5550 4925);
FORCEPROP 0 LAST $SEC 1
J 0
(-5150 4975);
DISPLAY 0.680851 (-5150 4975);
PAINT MONO (-5150 4975);
DISPLAY INVISIBLE (-5150 4975);
FORCEPROP 0 LAST CDS_SEC 1
J 0
(-5150 4975);
DISPLAY 0.680851 (-5150 4975);
DISPLAY INVISIBLE (-5150 4975);
FORCEPROP 1 LASTPIN (-5450 4925) $PN 1
J 0
(-5438 4937);
DISPLAY 0.787234 (-5438 4937);
PAINT MONO (-5438 4937);
FORCEPROP 1 LASTPIN (-5250 4925) $PN 2
J 0
(-5288 4937);
DISPLAY 0.787234 (-5288 4937);
PAINT MONO (-5288 4937);
FORCEPROP 1 LAST VALUE 2K
J 2
(-5200 4925);
DISPLAY 0.510638 (-5200 4925);
FORCEPROP 1 LAST MATERIAL CHIP
J 0
(-5150 4925);
DISPLAY 0.638298 (-5150 4925);
FORCEPROP 2 LAST CDS_LIB pure_quanta
J 0
(-5350 4925);
DISPLAY INVISIBLE (-5350 4925);
FORCEPROP 1 LAST TOLERANCE 1%
J 0
(-4975 4975);
DISPLAY 0.510638 (-4975 4975);
DISPLAY INVISIBLE (-4975 4975);
FORCEPROP 1 LAST WATTAGE 1/16W
J 0
(-4700 4975);
DISPLAY 0.510638 (-4700 4975);
DISPLAY INVISIBLE (-4700 4975);
FORCEPROP 1 LAST PACK_TYPE 0402LF
J 0
(-4875 4975);
DISPLAY 0.510638 (-4875 4975);
DISPLAY INVISIBLE (-4875 4975);
FORCEPROP 1 LAST PATH I154
J 0
(-5400 5075);
DISPLAY 0.978723 (-5400 5075);
PAINT WHITE (-5400 5075);
DISPLAY INVISIBLE (-5400 5075);
FORCEPROP 1 LAST PART_NUMBER CS22002FB07
J 0
(-4975 5000);
DISPLAY 0.510638 (-4975 5000);
DISPLAY INVISIBLE (-4975 5000);
FORCEADD OFFPAGE..1
(-6100 4925);
FORCEPROP 2 LAST $XR1 85 
J 0
(-6441 4925);
DISPLAY 0.638298 (-6441 4925);
PAINT MONO (-6441 4925);
FORCEPROP 2 LAST $XR0 81 
J 0
(-6351 4925);
DISPLAY 0.638298 (-6351 4925);
PAINT MONO (-6351 4925);
FORCEPROP 2 LAST CDS_LIB standard
J 0
(-6100 4925);
DISPLAY INVISIBLE (-6100 4925);
FORCEPROP 1 LAST OFFPAGE TRUE
J 0
(-5770 4795);
PAINT GREEN (-5770 4795);
DISPLAY INVISIBLE (-5770 4795);
FORCEPROP 1 LAST COMMENT_BODY TRUE
J 0
(-5970 4825);
DISPLAY 1.106383 (-5970 4825);
PAINT PEACH (-5970 4825);
DISPLAY INVISIBLE (-5970 4825);
FORCEPROP 2 LAST PATH I155
J 0
(-6050 5000);
DISPLAY 0.680851 (-6050 5000);
DISPLAY INVISIBLE (-6050 5000);
FORCEADD Q_RES..1
(-7050 4925);
FORCEPROP 1 LAST LOCATION R134
J 0
(-7350 4925);
DISPLAY 0.489362 (-7350 4925);
PAINT SKYBLUE (-7350 4925);
FORCEPROP 0 LAST $SEC 1
J 0
(-6925 4950);
DISPLAY 0.680851 (-6925 4950);
PAINT MONO (-6925 4950);
DISPLAY INVISIBLE (-6925 4950);
FORCEPROP 0 LAST CDS_SEC 1
J 0
(-6925 4950);
DISPLAY 0.680851 (-6925 4950);
DISPLAY INVISIBLE (-6925 4950);
FORCEPROP 1 LASTPIN (-7150 4925) $PN 1
J 0
(-7138 4937);
DISPLAY 0.787234 (-7138 4937);
PAINT MONO (-7138 4937);
FORCEPROP 1 LASTPIN (-6950 4925) $PN 2
J 0
(-6988 4937);
DISPLAY 0.787234 (-6988 4937);
PAINT MONO (-6988 4937);
FORCEPROP 1 LAST MATERIAL EMPTY
J 0
(-6950 4900);
DISPLAY 0.489362 (-6950 4900);
PAINT RED (-6950 4900);
FORCEPROP 1 LAST VALUE 4.7K
J 0
(-6925 4925);
DISPLAY 0.489362 (-6925 4925);
PAINT SKYBLUE (-6925 4925);
FORCEPROP 1 LAST WATTAGE 1/16W
J 2
(-7075 4775);
DISPLAY 0.510638 (-7075 4775);
PAINT SKYBLUE (-7075 4775);
DISPLAY INVISIBLE (-7075 4775);
FORCEPROP 1 LAST TOLERANCE 5%
J 0
(-6925 4925);
DISPLAY 0.510638 (-6925 4925);
PAINT SKYBLUE (-6925 4925);
DISPLAY INVISIBLE (-6925 4925);
FORCEPROP 1 LAST PACK_TYPE 0402LF
J 0
(-6800 4775);
DISPLAY 0.510638 (-6800 4775);
PAINT SKYBLUE (-6800 4775);
DISPLAY INVISIBLE (-6800 4775);
FORCEPROP 2 LAST CDS_LIB pure_quanta
J 0
(-7050 4925);
DISPLAY INVISIBLE (-7050 4925);
FORCEPROP 1 LAST PATH I156
J 0
(-7100 5075);
DISPLAY 0.978723 (-7100 5075);
PAINT WHITE (-7100 5075);
DISPLAY INVISIBLE (-7100 5075);
FORCEPROP 1 LAST PART_NUMBER CS24702JB10
J 0
(-7100 5025);
DISPLAY 0.510638 (-7100 5025);
PAINT SKYBLUE (-7100 5025);
DISPLAY INVISIBLE (-7100 5025);
FORCEADD Q_RES..1
(-7050 4875);
FORCEPROP 1 LAST LOCATION R135
J 0
(-7350 4875);
DISPLAY 0.489362 (-7350 4875);
PAINT SKYBLUE (-7350 4875);
FORCEPROP 0 LAST $SEC 1
J 0
(-6925 4900);
DISPLAY 0.680851 (-6925 4900);
PAINT MONO (-6925 4900);
DISPLAY INVISIBLE (-6925 4900);
FORCEPROP 0 LAST CDS_SEC 1
J 0
(-6925 4900);
DISPLAY 0.680851 (-6925 4900);
DISPLAY INVISIBLE (-6925 4900);
FORCEPROP 1 LASTPIN (-7150 4875) $PN 1
J 0
(-7138 4887);
DISPLAY 0.787234 (-7138 4887);
PAINT MONO (-7138 4887);
FORCEPROP 1 LASTPIN (-6950 4875) $PN 2
J 0
(-6988 4887);
DISPLAY 0.787234 (-6988 4887);
PAINT MONO (-6988 4887);
FORCEPROP 1 LAST VALUE 4.7K
J 0
(-6925 4875);
DISPLAY 0.489362 (-6925 4875);
PAINT SKYBLUE (-6925 4875);
FORCEPROP 1 LAST MATERIAL EMPTY
J 0
(-6950 4850);
DISPLAY 0.489362 (-6950 4850);
PAINT RED (-6950 4850);
FORCEPROP 1 LAST PACK_TYPE 0402LF
J 0
(-6800 4725);
DISPLAY 0.510638 (-6800 4725);
PAINT SKYBLUE (-6800 4725);
DISPLAY INVISIBLE (-6800 4725);
FORCEPROP 1 LAST TOLERANCE 5%
J 0
(-6925 4875);
DISPLAY 0.510638 (-6925 4875);
PAINT SKYBLUE (-6925 4875);
DISPLAY INVISIBLE (-6925 4875);
FORCEPROP 1 LAST WATTAGE 1/16W
J 2
(-7075 4725);
DISPLAY 0.510638 (-7075 4725);
PAINT SKYBLUE (-7075 4725);
DISPLAY INVISIBLE (-7075 4725);
FORCEPROP 2 LAST CDS_LIB pure_quanta
J 0
(-7050 4875);
DISPLAY INVISIBLE (-7050 4875);
FORCEPROP 1 LAST PATH I157
J 0
(-7100 5025);
DISPLAY 0.978723 (-7100 5025);
PAINT WHITE (-7100 5025);
DISPLAY INVISIBLE (-7100 5025);
FORCEPROP 1 LAST PART_NUMBER CS24702JB10
J 0
(-7100 4975);
DISPLAY 0.510638 (-7100 4975);
PAINT SKYBLUE (-7100 4975);
DISPLAY INVISIBLE (-7100 4975);
FORCEADD OFFPAGE..5
(-8200 4925);
FORCEPROP 2 LAST $XR2 161 
J 0
(-8664 4925);
DISPLAY 0.638298 (-8664 4925);
PAINT MONO (-8664 4925);
FORCEPROP 2 LAST $XR1 83 
J 0
(-8544 4925);
DISPLAY 0.638298 (-8544 4925);
PAINT MONO (-8544 4925);
FORCEPROP 2 LAST $XR0 82 
J 0
(-8454 4925);
DISPLAY 0.638298 (-8454 4925);
PAINT MONO (-8454 4925);
FORCEPROP 2 LAST CDS_LIB standard
J 0
(-8200 4925);
DISPLAY INVISIBLE (-8200 4925);
FORCEPROP 1 LAST OFFPAGE TRUE
J 0
(-7875 4800);
DISPLAY 0.872340 (-7875 4800);
PAINT GREEN (-7875 4800);
DISPLAY INVISIBLE (-7875 4800);
FORCEPROP 1 LAST COMMENT_BODY TRUE
J 0
(-8100 4850);
DISPLAY 0.872340 (-8100 4850);
PAINT GREEN (-8100 4850);
DISPLAY INVISIBLE (-8100 4850);
FORCEPROP 2 LAST PATH I158
J 0
(-8150 5000);
DISPLAY 0.680851 (-8150 5000);
DISPLAY INVISIBLE (-8150 5000);
FORCEADD OFFPAGE..5
(-8200 4875);
FORCEPROP 2 LAST $XR2 161 
J 0
(-8664 4875);
DISPLAY 0.638298 (-8664 4875);
PAINT MONO (-8664 4875);
FORCEPROP 2 LAST $XR1 83 
J 0
(-8544 4875);
DISPLAY 0.638298 (-8544 4875);
PAINT MONO (-8544 4875);
FORCEPROP 2 LAST $XR0 82 
J 0
(-8454 4875);
DISPLAY 0.638298 (-8454 4875);
PAINT MONO (-8454 4875);
FORCEPROP 2 LAST CDS_LIB standard
J 0
(-8200 4875);
DISPLAY INVISIBLE (-8200 4875);
FORCEPROP 1 LAST OFFPAGE TRUE
J 0
(-7875 4750);
DISPLAY 0.872340 (-7875 4750);
PAINT GREEN (-7875 4750);
DISPLAY INVISIBLE (-7875 4750);
FORCEPROP 1 LAST COMMENT_BODY TRUE
J 0
(-8100 4800);
DISPLAY 0.872340 (-8100 4800);
PAINT GREEN (-8100 4800);
DISPLAY INVISIBLE (-8100 4800);
FORCEPROP 2 LAST PATH I159
J 0
(-8150 4950);
DISPLAY 0.680851 (-8150 4950);
DISPLAY INVISIBLE (-8150 4950);
FORCEADD OFFPAGE..5
(-8200 5325);
FORCEPROP 2 LAST $XR1 82 
J 0
(-8575 5325);
DISPLAY 0.638298 (-8575 5325);
PAINT MONO (-8575 5325);
FORCEPROP 2 LAST $XR0 224 
J 0
(-8485 5325);
DISPLAY 0.638298 (-8485 5325);
PAINT MONO (-8485 5325);
FORCEPROP 2 LAST CDS_LIB standard
J 0
(-8200 5325);
DISPLAY INVISIBLE (-8200 5325);
FORCEPROP 1 LAST OFFPAGE TRUE
J 0
(-7875 5200);
DISPLAY 0.872340 (-7875 5200);
PAINT GREEN (-7875 5200);
DISPLAY INVISIBLE (-7875 5200);
FORCEPROP 1 LAST COMMENT_BODY TRUE
J 0
(-8100 5250);
DISPLAY 0.872340 (-8100 5250);
PAINT GREEN (-8100 5250);
DISPLAY INVISIBLE (-8100 5250);
FORCEPROP 2 LAST PATH I16
J 0
(-8475 5375);
DISPLAY 0.680851 (-8475 5375);
DISPLAY INVISIBLE (-8475 5375);
FORCEADD OFFPAGE..1
R 2
(-2225 3850);
FORCEPROP 2 LAST $XR2 161 
J 0
(-1859 3850);
DISPLAY 0.638298 (-1859 3850);
PAINT MONO (-1859 3850);
FORCEPROP 2 LAST $XR1 83 
J 0
(-1949 3850);
DISPLAY 0.638298 (-1949 3850);
PAINT MONO (-1949 3850);
FORCEPROP 2 LAST $XR0 82 
J 0
(-2039 3850);
DISPLAY 0.638298 (-2039 3850);
PAINT MONO (-2039 3850);
FORCEPROP 2 LAST CDS_LIB standard
J 0
(-2225 3850);
DISPLAY INVISIBLE (-2225 3850);
FORCEPROP 1 LAST OFFPAGE TRUE
J 2
(-2550 3725);
DISPLAY 0.872340 (-2550 3725);
PAINT GREEN (-2550 3725);
DISPLAY INVISIBLE (-2550 3725);
FORCEPROP 1 LAST COMMENT_BODY TRUE
J 2
(-2350 3750);
DISPLAY 0.872340 (-2350 3750);
PAINT GREEN (-2350 3750);
DISPLAY INVISIBLE (-2350 3750);
FORCEPROP 2 LAST PATH I160
J 0
(-2050 3925);
DISPLAY 0.680851 (-2050 3925);
DISPLAY INVISIBLE (-2050 3925);
FORCEADD OFFPAGE..1
R 2
(-2225 3800);
FORCEPROP 2 LAST $XR2 161 
J 0
(-1859 3800);
DISPLAY 0.638298 (-1859 3800);
PAINT MONO (-1859 3800);
FORCEPROP 2 LAST $XR1 83 
J 0
(-1949 3800);
DISPLAY 0.638298 (-1949 3800);
PAINT MONO (-1949 3800);
FORCEPROP 2 LAST $XR0 82 
J 0
(-2039 3800);
DISPLAY 0.638298 (-2039 3800);
PAINT MONO (-2039 3800);
FORCEPROP 2 LAST CDS_LIB standard
J 0
(-2225 3800);
DISPLAY INVISIBLE (-2225 3800);
FORCEPROP 1 LAST OFFPAGE TRUE
J 2
(-2550 3675);
DISPLAY 0.872340 (-2550 3675);
PAINT GREEN (-2550 3675);
DISPLAY INVISIBLE (-2550 3675);
FORCEPROP 1 LAST COMMENT_BODY TRUE
J 2
(-2350 3700);
DISPLAY 0.872340 (-2350 3700);
PAINT GREEN (-2350 3700);
DISPLAY INVISIBLE (-2350 3700);
FORCEPROP 2 LAST PATH I161
J 0
(-2050 3875);
DISPLAY 0.680851 (-2050 3875);
DISPLAY INVISIBLE (-2050 3875);
FORCEADD Q_RES..2
(-4050 3250);
FORCEPROP 1 LAST LOCATION R136
J 0
(-4005 3375);
DISPLAY 0.510638 (-4005 3375);
FORCEPROP 0 LAST $SEC 1
J 0
(-4000 3400);
DISPLAY 0.680851 (-4000 3400);
PAINT MONO (-4000 3400);
DISPLAY INVISIBLE (-4000 3400);
FORCEPROP 0 LAST CDS_SEC 1
J 0
(-4000 3400);
DISPLAY 0.680851 (-4000 3400);
DISPLAY INVISIBLE (-4000 3400);
FORCEPROP 1 LASTPIN (-4050 3350) $PN 1
J 0
(-4045 3312);
DISPLAY 0.787234 (-4045 3312);
PAINT MONO (-4045 3312);
FORCEPROP 1 LASTPIN (-4050 3150) $PN 2
J 0
(-4045 3160);
DISPLAY 0.787234 (-4045 3160);
PAINT MONO (-4045 3160);
FORCEPROP 1 LAST MATERIAL EMPTY
J 0
(-4010 3175);
DISPLAY 0.510638 (-4010 3175);
FORCEPROP 1 LAST PACK_TYPE 0402LF
J 0
(-4010 3075);
DISPLAY 0.510638 (-4010 3075);
FORCEPROP 1 LAST WATTAGE 1/16W
J 0
(-4010 3225);
DISPLAY 0.510638 (-4010 3225);
FORCEPROP 1 LAST VALUE 10K
J 0
(-4005 3325);
DISPLAY 0.510638 (-4005 3325);
FORCEPROP 1 LAST TOLERANCE 1%
J 0
(-4005 3275);
DISPLAY 0.510638 (-4005 3275);
FORCEPROP 2 LAST CDS_LIB pure_quanta
J 0
(-4050 3250);
DISPLAY INVISIBLE (-4050 3250);
FORCEPROP 1 LAST PATH I162
J 0
(-4000 3425);
DISPLAY 0.978723 (-4000 3425);
PAINT WHITE (-4000 3425);
DISPLAY INVISIBLE (-4000 3425);
FORCEPROP 1 LAST PART_NUMBER CS31002FB08
J 0
(-4010 3125);
DISPLAY 0.510638 (-4010 3125);
DISPLAY INVISIBLE (-4010 3125);
FORCEADD Q_RES..2
(-4250 3250);
FORCEPROP 1 LAST LOCATION R126
J 0
(-4225 3375);
DISPLAY 0.489362 (-4225 3375);
PAINT SKYBLUE (-4225 3375);
FORCEPROP 0 LAST $SEC 1
J 0
(-4225 3400);
DISPLAY 0.680851 (-4225 3400);
PAINT MONO (-4225 3400);
DISPLAY INVISIBLE (-4225 3400);
FORCEPROP 0 LAST CDS_SEC 1
J 0
(-4225 3400);
DISPLAY 0.680851 (-4225 3400);
DISPLAY INVISIBLE (-4225 3400);
FORCEPROP 1 LASTPIN (-4250 3350) $PN 1
J 0
(-4245 3312);
DISPLAY 0.787234 (-4245 3312);
PAINT MONO (-4245 3312);
FORCEPROP 1 LASTPIN (-4250 3150) $PN 2
J 0
(-4245 3160);
DISPLAY 0.787234 (-4245 3160);
PAINT MONO (-4245 3160);
FORCEPROP 1 LAST VALUE 10K
J 0
(-4205 3325);
DISPLAY 0.489362 (-4205 3325);
PAINT SKYBLUE (-4205 3325);
FORCEPROP 1 LAST TOLERANCE 1%
J 0
(-4205 3275);
DISPLAY 0.489362 (-4205 3275);
PAINT SKYBLUE (-4205 3275);
FORCEPROP 1 LAST WATTAGE 1/16W
J 0
(-4210 3225);
DISPLAY 0.489362 (-4210 3225);
PAINT SKYBLUE (-4210 3225);
FORCEPROP 1 LAST MATERIAL CHIP
J 0
(-4210 3175);
DISPLAY 0.489362 (-4210 3175);
PAINT SKYBLUE (-4210 3175);
FORCEPROP 1 LAST PACK_TYPE 0402LF
J 0
(-4200 3125);
DISPLAY 0.489362 (-4200 3125);
PAINT SKYBLUE (-4200 3125);
FORCEPROP 2 LAST CDS_LIB pure_quanta
J 0
(-4250 3250);
DISPLAY INVISIBLE (-4250 3250);
FORCEPROP 2 LAST BOM_COST MEM
J 0
(-4200 3425);
DISPLAY 0.808511 (-4200 3425);
DISPLAY INVISIBLE (-4200 3425);
FORCEPROP 1 LAST PATH I163
J 0
(-4200 3425);
DISPLAY 0.978723 (-4200 3425);
PAINT WHITE (-4200 3425);
DISPLAY INVISIBLE (-4200 3425);
FORCEPROP 1 LAST PART_NUMBER CS31002FB08
J 0
(-4210 3125);
DISPLAY 0.489362 (-4210 3125);
PAINT SKYBLUE (-4210 3125);
DISPLAY INVISIBLE (-4210 3125);
FORCEADD GND..1
(-4050 3000);
FORCEPROP 3 LASTPIN (-4050 3050) SIG_NAME GND\g
J 0
(-4040 3060);
DISPLAY 0.659574 (-4040 3060);
PAINT MONO (-4040 3060);
DISPLAY INVISIBLE (-4040 3060);
FORCEPROP 2 LAST CDS_LIB pure_quanta_power
J 0
(-4050 3000);
DISPLAY INVISIBLE (-4050 3000);
FORCEPROP 1 LAST SIZE 1B
J 0
(-3975 2950);
DISPLAY 0.851064 (-3975 2950);
PAINT GREEN (-3975 2950);
DISPLAY INVISIBLE (-3975 2950);
FORCEPROP 2 LAST BOM_COST MEM
J 0
(-4150 3075);
DISPLAY 0.808511 (-4150 3075);
DISPLAY INVISIBLE (-4150 3075);
FORCEPROP 1 LAST HDL_POWER GND
J 0
(-4050 3150);
DISPLAY 0.851064 (-4050 3150);
PAINT GREEN (-4050 3150);
DISPLAY INVISIBLE (-4050 3150);
FORCEPROP 1 LAST PATH I164
J 0
(-3975 3000);
DISPLAY 0.872340 (-3975 3000);
PAINT AQUA (-3975 3000);
DISPLAY INVISIBLE (-3975 3000);
FORCEADD GND..1
(-4250 3000);
FORCEPROP 3 LASTPIN (-4250 3050) SIG_NAME GND\g
J 0
(-4240 3060);
DISPLAY 0.659574 (-4240 3060);
PAINT MONO (-4240 3060);
DISPLAY INVISIBLE (-4240 3060);
FORCEPROP 1 LAST SIZE 1B
J 0
(-4175 2950);
DISPLAY 0.851064 (-4175 2950);
PAINT GREEN (-4175 2950);
DISPLAY INVISIBLE (-4175 2950);
FORCEPROP 2 LAST BOM_COST MEM
J 0
(-4350 3075);
DISPLAY 0.808511 (-4350 3075);
DISPLAY INVISIBLE (-4350 3075);
FORCEPROP 2 LAST CDS_LIB pure_quanta_power
J 0
(-4250 3000);
DISPLAY INVISIBLE (-4250 3000);
FORCEPROP 1 LAST HDL_POWER GND
J 0
(-4250 3150);
DISPLAY 0.851064 (-4250 3150);
PAINT GREEN (-4250 3150);
DISPLAY INVISIBLE (-4250 3150);
FORCEPROP 1 LAST PATH I165
J 0
(-4175 3000);
DISPLAY 0.872340 (-4175 3000);
PAINT AQUA (-4175 3000);
DISPLAY INVISIBLE (-4175 3000);
FORCEADD Q_RES..1
(-7075 3000);
FORCEPROP 1 LAST LOCATION R64
J 0
(-7300 3000);
DISPLAY 0.638298 (-7300 3000);
FORCEPROP 0 LAST $SEC 1
J 0
(-6825 3050);
DISPLAY 0.680851 (-6825 3050);
PAINT MONO (-6825 3050);
DISPLAY INVISIBLE (-6825 3050);
FORCEPROP 0 LAST CDS_SEC 1
J 0
(-6825 3050);
DISPLAY 0.680851 (-6825 3050);
DISPLAY INVISIBLE (-6825 3050);
FORCEPROP 1 LASTPIN (-7175 3000) $PN 1
J 0
(-7163 3012);
DISPLAY 0.787234 (-7163 3012);
PAINT MONO (-7163 3012);
FORCEPROP 1 LASTPIN (-6975 3000) $PN 2
J 0
(-7013 3012);
DISPLAY 0.787234 (-7013 3012);
PAINT MONO (-7013 3012);
FORCEPROP 1 LAST MATERIAL EMPTY
J 0
(-7125 2950);
DISPLAY 0.638298 (-7125 2950);
FORCEPROP 1 LAST VALUE 1K
J 2
(-6875 3000);
DISPLAY 0.638298 (-6875 3000);
FORCEPROP 1 LAST TOLERANCE 1%
J 0
(-6825 3000);
DISPLAY 0.638298 (-6825 3000);
FORCEPROP 1 LAST PACK_TYPE 0402LF
J 0
(-7150 2825);
DISPLAY 0.978723 (-7150 2825);
DISPLAY INVISIBLE (-7150 2825);
FORCEPROP 1 LAST WATTAGE 1/16W
J 2
(-7100 2850);
DISPLAY 0.978723 (-7100 2850);
DISPLAY INVISIBLE (-7100 2850);
FORCEPROP 2 LAST CDS_LIB pure_quanta
J 0
(-7075 3000);
DISPLAY INVISIBLE (-7075 3000);
FORCEPROP 1 LAST PATH I166
J 0
(-7125 3150);
DISPLAY 0.978723 (-7125 3150);
PAINT WHITE (-7125 3150);
DISPLAY INVISIBLE (-7125 3150);
FORCEPROP 1 LAST PART_NUMBER CS21002FB06
J 0
(-7125 3100);
DISPLAY 0.978723 (-7125 3100);
DISPLAY INVISIBLE (-7125 3100);
FORCEADD OFFPAGE..1
R 2
(-2225 3925);
FORCEPROP 2 LAST $XR1 153 
J 0
(-1949 3925);
DISPLAY 0.638298 (-1949 3925);
PAINT MONO (-1949 3925);
FORCEPROP 2 LAST $XR0 81 
J 0
(-2039 3925);
DISPLAY 0.638298 (-2039 3925);
PAINT MONO (-2039 3925);
FORCEPROP 2 LAST CDS_LIB standard
J 0
(-2225 3925);
DISPLAY INVISIBLE (-2225 3925);
FORCEPROP 1 LAST OFFPAGE TRUE
J 2
(-2550 3800);
DISPLAY 0.872340 (-2550 3800);
PAINT GREEN (-2550 3800);
DISPLAY INVISIBLE (-2550 3800);
FORCEPROP 1 LAST COMMENT_BODY TRUE
J 2
(-2350 3825);
DISPLAY 0.872340 (-2350 3825);
PAINT GREEN (-2350 3825);
DISPLAY INVISIBLE (-2350 3825);
FORCEPROP 2 LAST PATH I167
J 0
(-2050 4000);
DISPLAY 0.680851 (-2050 4000);
DISPLAY INVISIBLE (-2050 4000);
FORCEADD GND..1
(-4475 3000);
FORCEPROP 3 LASTPIN (-4475 3050) SIG_NAME GND\g
J 0
(-4465 3060);
DISPLAY 0.659574 (-4465 3060);
PAINT MONO (-4465 3060);
DISPLAY INVISIBLE (-4465 3060);
FORCEPROP 2 LAST CDS_LIB pure_quanta_power
J 0
(-4475 3000);
DISPLAY INVISIBLE (-4475 3000);
FORCEPROP 1 LAST SIZE 1B
J 0
(-4400 2950);
DISPLAY 0.851064 (-4400 2950);
PAINT GREEN (-4400 2950);
DISPLAY INVISIBLE (-4400 2950);
FORCEPROP 2 LAST BOM_COST MEM
J 0
(-4575 3075);
DISPLAY 0.808511 (-4575 3075);
DISPLAY INVISIBLE (-4575 3075);
FORCEPROP 1 LAST HDL_POWER GND
J 0
(-4475 3150);
DISPLAY 0.851064 (-4475 3150);
PAINT GREEN (-4475 3150);
DISPLAY INVISIBLE (-4475 3150);
FORCEPROP 1 LAST PATH I169
J 0
(-4400 3000);
DISPLAY 0.872340 (-4400 3000);
PAINT AQUA (-4400 3000);
DISPLAY INVISIBLE (-4400 3000);
FORCEADD OFFPAGE..5
(-8200 5250);
FORCEPROP 2 LAST $XR1 81 
J 0
(-8575 5250);
DISPLAY 0.638298 (-8575 5250);
PAINT MONO (-8575 5250);
FORCEPROP 2 LAST $XR0 172 
J 0
(-8485 5250);
DISPLAY 0.638298 (-8485 5250);
PAINT MONO (-8485 5250);
FORCEPROP 2 LAST CDS_LIB standard
J 0
(-8200 5250);
DISPLAY INVISIBLE (-8200 5250);
FORCEPROP 1 LAST OFFPAGE TRUE
J 0
(-7875 5125);
DISPLAY 0.872340 (-7875 5125);
PAINT GREEN (-7875 5125);
DISPLAY INVISIBLE (-7875 5125);
FORCEPROP 1 LAST COMMENT_BODY TRUE
J 0
(-8100 5175);
DISPLAY 0.872340 (-8100 5175);
PAINT GREEN (-8100 5175);
DISPLAY INVISIBLE (-8100 5175);
FORCEPROP 2 LAST PATH I17
J 0
(-8475 5300);
DISPLAY 0.680851 (-8475 5300);
DISPLAY INVISIBLE (-8475 5300);
FORCEADD Q_RES..2
(-4475 3275);
FORCEPROP 1 LAST LOCATION R8033
J 0
(-4430 3400);
DISPLAY 0.510638 (-4430 3400);
FORCEPROP 0 LAST $SEC 1
J 0
(-4425 3425);
DISPLAY 0.680851 (-4425 3425);
PAINT MONO (-4425 3425);
DISPLAY INVISIBLE (-4425 3425);
FORCEPROP 0 LAST CDS_SEC 1
J 0
(-4425 3425);
DISPLAY 0.680851 (-4425 3425);
DISPLAY INVISIBLE (-4425 3425);
FORCEPROP 1 LASTPIN (-4475 3375) $PN 1
J 0
(-4470 3337);
DISPLAY 0.787234 (-4470 3337);
PAINT MONO (-4470 3337);
FORCEPROP 1 LASTPIN (-4475 3175) $PN 2
J 0
(-4470 3185);
DISPLAY 0.787234 (-4470 3185);
PAINT MONO (-4470 3185);
FORCEPROP 1 LAST WATTAGE 1/16W
J 0
(-4435 3250);
DISPLAY 0.510638 (-4435 3250);
FORCEPROP 1 LAST PACK_TYPE 0402LF
J 0
(-4425 3150);
DISPLAY 0.510638 (-4425 3150);
FORCEPROP 1 LAST MATERIAL CHIP
J 0
(-4435 3200);
DISPLAY 0.510638 (-4435 3200);
FORCEPROP 1 LAST TOLERANCE 1%
J 0
(-4430 3300);
DISPLAY 0.510638 (-4430 3300);
FORCEPROP 1 LAST VALUE 1K
J 0
(-4430 3350);
DISPLAY 0.510638 (-4430 3350);
FORCEPROP 2 LAST CDS_LIB pure_quanta
J 0
(-4475 3275);
DISPLAY INVISIBLE (-4475 3275);
FORCEPROP 1 LAST PATH I170
J 0
(-4425 3450);
DISPLAY 0.978723 (-4425 3450);
PAINT WHITE (-4425 3450);
DISPLAY INVISIBLE (-4425 3450);
FORCEPROP 1 LAST PART_NUMBER CS21002FB06
J 0
(-4435 3150);
DISPLAY 0.978723 (-4435 3150);
DISPLAY INVISIBLE (-4435 3150);
FORCEADD Q_RES..1
(-7050 4575);
FORCEPROP 1 LAST LOCATION R1304
J 0
(-7350 4575);
DISPLAY 0.489362 (-7350 4575);
PAINT SKYBLUE (-7350 4575);
FORCEPROP 0 LAST $SEC 1
J 0
(-6925 4600);
DISPLAY 0.680851 (-6925 4600);
PAINT MONO (-6925 4600);
DISPLAY INVISIBLE (-6925 4600);
FORCEPROP 0 LAST CDS_SEC 1
J 0
(-6925 4600);
DISPLAY 0.680851 (-6925 4600);
DISPLAY INVISIBLE (-6925 4600);
FORCEPROP 1 LASTPIN (-7150 4575) $PN 1
J 0
(-7138 4587);
DISPLAY 0.787234 (-7138 4587);
PAINT MONO (-7138 4587);
FORCEPROP 1 LASTPIN (-6950 4575) $PN 2
J 0
(-6988 4587);
DISPLAY 0.787234 (-6988 4587);
PAINT MONO (-6988 4587);
FORCEPROP 1 LAST VALUE 10K
J 0
(-6925 4575);
DISPLAY 0.489362 (-6925 4575);
PAINT SKYBLUE (-6925 4575);
FORCEPROP 2 LAST CDS_LIB pure_quanta
J 0
(-7050 4575);
DISPLAY INVISIBLE (-7050 4575);
FORCEPROP 1 LAST PACK_TYPE 0402LF
J 0
(-6800 4425);
DISPLAY 0.510638 (-6800 4425);
PAINT SKYBLUE (-6800 4425);
DISPLAY INVISIBLE (-6800 4425);
FORCEPROP 1 LAST MATERIAL CHIP
J 0
(-6950 4550);
DISPLAY 0.489362 (-6950 4550);
PAINT SKYBLUE (-6950 4550);
DISPLAY INVISIBLE (-6950 4550);
FORCEPROP 1 LAST WATTAGE 1/16W
J 2
(-7075 4425);
DISPLAY 0.510638 (-7075 4425);
PAINT SKYBLUE (-7075 4425);
DISPLAY INVISIBLE (-7075 4425);
FORCEPROP 1 LAST TOLERANCE 1%
J 0
(-6925 4575);
DISPLAY 0.510638 (-6925 4575);
PAINT SKYBLUE (-6925 4575);
DISPLAY INVISIBLE (-6925 4575);
FORCEPROP 1 LAST PATH I171
J 0
(-7100 4725);
DISPLAY 0.978723 (-7100 4725);
PAINT WHITE (-7100 4725);
DISPLAY INVISIBLE (-7100 4725);
FORCEPROP 1 LAST PART_NUMBER CS31002FB08
J 0
(-7100 4675);
DISPLAY 0.510638 (-7100 4675);
PAINT SKYBLUE (-7100 4675);
DISPLAY INVISIBLE (-7100 4675);
FORCEADD OFFPAGE..5
(-8200 5425);
FORCEPROP 2 LAST $XR1 82 
J 0
(-8575 5425);
DISPLAY 0.638298 (-8575 5425);
PAINT MONO (-8575 5425);
FORCEPROP 2 LAST $XR0 217 
J 0
(-8485 5425);
DISPLAY 0.638298 (-8485 5425);
PAINT MONO (-8485 5425);
FORCEPROP 2 LAST CDS_LIB standard
J 0
(-8200 5425);
DISPLAY INVISIBLE (-8200 5425);
FORCEPROP 1 LAST OFFPAGE TRUE
J 0
(-7875 5300);
DISPLAY 0.872340 (-7875 5300);
PAINT GREEN (-7875 5300);
DISPLAY INVISIBLE (-7875 5300);
FORCEPROP 1 LAST COMMENT_BODY TRUE
J 0
(-8100 5350);
DISPLAY 0.872340 (-8100 5350);
PAINT GREEN (-8100 5350);
DISPLAY INVISIBLE (-8100 5350);
FORCEPROP 2 LAST PATH I18
J 0
(-8475 5475);
DISPLAY 0.680851 (-8475 5475);
DISPLAY INVISIBLE (-8475 5475);
FORCEADD OFFPAGE..5
(-8200 5525);
FORCEPROP 2 LAST $XR1 82 
J 0
(-8575 5525);
DISPLAY 0.638298 (-8575 5525);
PAINT MONO (-8575 5525);
FORCEPROP 2 LAST $XR0 200 
J 0
(-8485 5525);
DISPLAY 0.638298 (-8485 5525);
PAINT MONO (-8485 5525);
FORCEPROP 2 LAST CDS_LIB standard
J 0
(-8200 5525);
DISPLAY INVISIBLE (-8200 5525);
FORCEPROP 1 LAST OFFPAGE TRUE
J 0
(-7875 5400);
DISPLAY 0.872340 (-7875 5400);
PAINT GREEN (-7875 5400);
DISPLAY INVISIBLE (-7875 5400);
FORCEPROP 1 LAST COMMENT_BODY TRUE
J 0
(-8100 5450);
DISPLAY 0.872340 (-8100 5450);
PAINT GREEN (-8100 5450);
DISPLAY INVISIBLE (-8100 5450);
FORCEPROP 2 LAST PATH I19
J 0
(-8475 5575);
DISPLAY 0.680851 (-8475 5575);
DISPLAY INVISIBLE (-8475 5575);
FORCEADD OFFPAGE..5
(-8200 5475);
FORCEPROP 2 LAST $XR1 82 
J 0
(-8575 5475);
DISPLAY 0.638298 (-8575 5475);
PAINT MONO (-8575 5475);
FORCEPROP 2 LAST $XR0 210 
J 0
(-8485 5475);
DISPLAY 0.638298 (-8485 5475);
PAINT MONO (-8485 5475);
FORCEPROP 2 LAST CDS_LIB standard
J 0
(-8200 5475);
DISPLAY INVISIBLE (-8200 5475);
FORCEPROP 1 LAST OFFPAGE TRUE
J 0
(-7875 5350);
DISPLAY 0.872340 (-7875 5350);
PAINT GREEN (-7875 5350);
DISPLAY INVISIBLE (-7875 5350);
FORCEPROP 1 LAST COMMENT_BODY TRUE
J 0
(-8100 5400);
DISPLAY 0.872340 (-8100 5400);
PAINT GREEN (-8100 5400);
DISPLAY INVISIBLE (-8100 5400);
FORCEPROP 2 LAST PATH I20
J 0
(-8475 5525);
DISPLAY 0.680851 (-8475 5525);
DISPLAY INVISIBLE (-8475 5525);
FORCEADD OFFPAGE..5
(-8200 5575);
FORCEPROP 2 LAST $XR1 81 
J 0
(-8575 5575);
DISPLAY 0.638298 (-8575 5575);
PAINT MONO (-8575 5575);
FORCEPROP 2 LAST $XR0 193 
J 0
(-8485 5575);
DISPLAY 0.638298 (-8485 5575);
PAINT MONO (-8485 5575);
FORCEPROP 2 LAST CDS_LIB standard
J 0
(-8200 5575);
DISPLAY INVISIBLE (-8200 5575);
FORCEPROP 1 LAST OFFPAGE TRUE
J 0
(-7875 5450);
DISPLAY 0.872340 (-7875 5450);
PAINT GREEN (-7875 5450);
DISPLAY INVISIBLE (-7875 5450);
FORCEPROP 1 LAST COMMENT_BODY TRUE
J 0
(-8100 5500);
DISPLAY 0.872340 (-8100 5500);
PAINT GREEN (-8100 5500);
DISPLAY INVISIBLE (-8100 5500);
FORCEPROP 2 LAST PATH I21
J 0
(-8475 5625);
DISPLAY 0.680851 (-8475 5625);
DISPLAY INVISIBLE (-8475 5625);
FORCEADD OFFPAGE..5
(-8200 5750);
FORCEPROP 2 LAST $XR1 29 
J 0
(-8544 5750);
DISPLAY 0.638298 (-8544 5750);
PAINT MONO (-8544 5750);
FORCEPROP 2 LAST $XR0 81 
J 0
(-8454 5750);
DISPLAY 0.638298 (-8454 5750);
PAINT MONO (-8454 5750);
FORCEPROP 2 LAST CDS_LIB standard
J 0
(-8200 5750);
DISPLAY INVISIBLE (-8200 5750);
FORCEPROP 1 LAST OFFPAGE TRUE
J 0
(-7875 5625);
DISPLAY 0.872340 (-7875 5625);
PAINT GREEN (-7875 5625);
DISPLAY INVISIBLE (-7875 5625);
FORCEPROP 1 LAST COMMENT_BODY TRUE
J 0
(-8100 5675);
DISPLAY 0.872340 (-8100 5675);
PAINT GREEN (-8100 5675);
DISPLAY INVISIBLE (-8100 5675);
FORCEPROP 2 LAST PATH I22
J 0
(-8450 5800);
DISPLAY 0.680851 (-8450 5800);
DISPLAY INVISIBLE (-8450 5800);
FORCEADD Q_RES..1
(-7075 3075);
FORCEPROP 1 LAST LOCATION R639
J 0
(-7275 3075);
DISPLAY 0.489362 (-7275 3075);
PAINT SKYBLUE (-7275 3075);
FORCEPROP 0 LAST $SEC 1
J 0
(-7225 3125);
DISPLAY 0.680851 (-7225 3125);
PAINT MONO (-7225 3125);
DISPLAY INVISIBLE (-7225 3125);
FORCEPROP 0 LAST CDS_SEC 1
J 0
(-7225 3125);
DISPLAY 1.021277 (-7225 3125);
DISPLAY INVISIBLE (-7225 3125);
FORCEPROP 1 LASTPIN (-7175 3075) $PN 1
J 0
(-7163 3087);
DISPLAY 0.489362 (-7163 3087);
PAINT MONO (-7163 3087);
FORCEPROP 1 LASTPIN (-6975 3075) $PN 2
J 0
(-7013 3087);
DISPLAY 0.489362 (-7013 3087);
PAINT MONO (-7013 3087);
FORCEPROP 1 LAST VALUE 1K
J 0
(-6975 3075);
DISPLAY 0.489362 (-6975 3075);
PAINT SKYBLUE (-6975 3075);
FORCEPROP 1 LAST TOLERANCE 1%
J 0
(-6950 3075);
DISPLAY 0.510638 (-6950 3075);
PAINT SKYBLUE (-6950 3075);
DISPLAY INVISIBLE (-6950 3075);
FORCEPROP 2 LAST CDS_LIB pure_quanta
J 0
(-7075 3075);
DISPLAY INVISIBLE (-7075 3075);
FORCEPROP 1 LAST WATTAGE 1/16W
J 2
(-7100 2925);
DISPLAY 0.510638 (-7100 2925);
PAINT SKYBLUE (-7100 2925);
DISPLAY INVISIBLE (-7100 2925);
FORCEPROP 1 LAST MATERIAL CHIP
J 0
(-6975 3050);
DISPLAY 0.489362 (-6975 3050);
PAINT SKYBLUE (-6975 3050);
DISPLAY INVISIBLE (-6975 3050);
FORCEPROP 1 LAST PACK_TYPE 0402LF
J 0
(-6825 2925);
DISPLAY 0.510638 (-6825 2925);
PAINT SKYBLUE (-6825 2925);
DISPLAY INVISIBLE (-6825 2925);
FORCEPROP 1 LAST PATH I33
J 0
(-7125 3225);
DISPLAY 0.978723 (-7125 3225);
PAINT WHITE (-7125 3225);
DISPLAY INVISIBLE (-7125 3225);
FORCEPROP 1 LAST PART_NUMBER CS21002FB06
J 0
(-7125 3175);
DISPLAY 0.510638 (-7125 3175);
PAINT SKYBLUE (-7125 3175);
DISPLAY INVISIBLE (-7125 3175);
FORCEADD Q_RES..1
(-7075 3125);
FORCEPROP 1 LAST LOCATION R638
J 0
(-7275 3125);
DISPLAY 0.489362 (-7275 3125);
PAINT SKYBLUE (-7275 3125);
FORCEPROP 0 LAST $SEC 1
J 0
(-7225 3175);
DISPLAY 0.680851 (-7225 3175);
PAINT MONO (-7225 3175);
DISPLAY INVISIBLE (-7225 3175);
FORCEPROP 0 LAST CDS_SEC 1
J 0
(-7225 3175);
DISPLAY 1.021277 (-7225 3175);
DISPLAY INVISIBLE (-7225 3175);
FORCEPROP 1 LASTPIN (-7175 3125) $PN 1
J 0
(-7163 3137);
DISPLAY 0.489362 (-7163 3137);
PAINT MONO (-7163 3137);
FORCEPROP 1 LASTPIN (-6975 3125) $PN 2
J 0
(-7013 3137);
DISPLAY 0.489362 (-7013 3137);
PAINT MONO (-7013 3137);
FORCEPROP 1 LAST VALUE 1K
J 0
(-6975 3125);
DISPLAY 0.489362 (-6975 3125);
PAINT SKYBLUE (-6975 3125);
FORCEPROP 1 LAST TOLERANCE 1%
J 0
(-6950 3125);
DISPLAY 0.510638 (-6950 3125);
PAINT SKYBLUE (-6950 3125);
DISPLAY INVISIBLE (-6950 3125);
FORCEPROP 2 LAST CDS_LIB pure_quanta
J 0
(-7075 3125);
DISPLAY INVISIBLE (-7075 3125);
FORCEPROP 1 LAST WATTAGE 1/16W
J 2
(-7100 2975);
DISPLAY 0.510638 (-7100 2975);
PAINT SKYBLUE (-7100 2975);
DISPLAY INVISIBLE (-7100 2975);
FORCEPROP 1 LAST MATERIAL CHIP
J 0
(-6975 3100);
DISPLAY 0.489362 (-6975 3100);
PAINT SKYBLUE (-6975 3100);
DISPLAY INVISIBLE (-6975 3100);
FORCEPROP 1 LAST PACK_TYPE 0402LF
J 0
(-6825 2975);
DISPLAY 0.510638 (-6825 2975);
PAINT SKYBLUE (-6825 2975);
DISPLAY INVISIBLE (-6825 2975);
FORCEPROP 1 LAST PATH I35
J 0
(-7125 3275);
DISPLAY 0.978723 (-7125 3275);
PAINT WHITE (-7125 3275);
DISPLAY INVISIBLE (-7125 3275);
FORCEPROP 1 LAST PART_NUMBER CS21002FB06
J 0
(-7125 3225);
DISPLAY 0.510638 (-7125 3225);
PAINT SKYBLUE (-7125 3225);
DISPLAY INVISIBLE (-7125 3225);
FORCEADD Q_RES..1
(-7050 3600);
FORCEPROP 1 LAST LOCATION R1195
J 0
(-7350 3600);
DISPLAY 0.489362 (-7350 3600);
PAINT SKYBLUE (-7350 3600);
FORCEPROP 0 LAST $SEC 1
J 0
(-7350 3650);
DISPLAY 0.680851 (-7350 3650);
PAINT MONO (-7350 3650);
DISPLAY INVISIBLE (-7350 3650);
FORCEPROP 0 LAST CDS_SEC 1
J 0
(-7350 3650);
DISPLAY 0.680851 (-7350 3650);
DISPLAY INVISIBLE (-7350 3650);
FORCEPROP 1 LASTPIN (-7150 3600) $PN 1
J 0
(-7138 3612);
DISPLAY 0.489362 (-7138 3612);
PAINT MONO (-7138 3612);
FORCEPROP 1 LASTPIN (-6950 3600) $PN 2
J 0
(-6988 3612);
DISPLAY 0.489362 (-6988 3612);
PAINT MONO (-6988 3612);
FORCEPROP 1 LAST VALUE 4.7K
J 0
(-6925 3600);
DISPLAY 0.489362 (-6925 3600);
PAINT SKYBLUE (-6925 3600);
FORCEPROP 1 LAST MATERIAL EMPTY
J 0
(-6950 3575);
DISPLAY 0.489362 (-6950 3575);
PAINT RED (-6950 3575);
FORCEPROP 1 LAST PACK_TYPE 0402LF
J 0
(-6800 3450);
DISPLAY 0.510638 (-6800 3450);
PAINT SKYBLUE (-6800 3450);
DISPLAY INVISIBLE (-6800 3450);
FORCEPROP 1 LAST TOLERANCE 5%
J 0
(-6925 3600);
DISPLAY 0.510638 (-6925 3600);
PAINT SKYBLUE (-6925 3600);
DISPLAY INVISIBLE (-6925 3600);
FORCEPROP 1 LAST WATTAGE 1/16W
J 2
(-7075 3450);
DISPLAY 0.510638 (-7075 3450);
PAINT SKYBLUE (-7075 3450);
DISPLAY INVISIBLE (-7075 3450);
FORCEPROP 2 LAST CDS_LIB pure_quanta
J 0
(-7050 3600);
DISPLAY INVISIBLE (-7050 3600);
FORCEPROP 1 LAST PATH I36
J 0
(-7100 3750);
DISPLAY 0.978723 (-7100 3750);
PAINT WHITE (-7100 3750);
DISPLAY INVISIBLE (-7100 3750);
FORCEPROP 1 LAST PART_NUMBER CS24702JB10
J 0
(-7100 3700);
DISPLAY 0.510638 (-7100 3700);
PAINT SKYBLUE (-7100 3700);
DISPLAY INVISIBLE (-7100 3700);
FORCEADD UNIVERSAL_POWER..1
R 2
(-6800 3325);
FORCEPROP 3 LASTPIN (-6800 3275) SIG_NAME P3V3_AUX\g
J 0
(-6790 3285);
DISPLAY 0.659574 (-6790 3285);
PAINT MONO (-6790 3285);
DISPLAY INVISIBLE (-6790 3285);
FORCEPROP 1 LAST HDL_POWER P3V3_AUX
J 1
(-6800 3375);
DISPLAY 0.489362 (-6800 3375);
PAINT GREEN (-6800 3375);
FORCEPROP 2 LAST CDS_LIB pure_quanta_power
J 2
(-6800 3325);
DISPLAY INVISIBLE (-6800 3325);
FORCEPROP 1 LAST PATH I37
J 2
(-6850 3350);
DISPLAY 0.872340 (-6850 3350);
PAINT AQUA (-6850 3350);
DISPLAY INVISIBLE (-6850 3350);
FORCEADD Q_RES..1
(-7050 3650);
FORCEPROP 1 LAST LOCATION R1071
J 0
(-7350 3650);
DISPLAY 0.489362 (-7350 3650);
PAINT SKYBLUE (-7350 3650);
FORCEPROP 0 LAST $SEC 1
J 0
(-7350 3700);
DISPLAY 0.680851 (-7350 3700);
PAINT MONO (-7350 3700);
DISPLAY INVISIBLE (-7350 3700);
FORCEPROP 0 LAST CDS_SEC 1
J 0
(-7350 3700);
DISPLAY 0.680851 (-7350 3700);
DISPLAY INVISIBLE (-7350 3700);
FORCEPROP 1 LASTPIN (-7150 3650) $PN 1
J 0
(-7138 3662);
DISPLAY 0.489362 (-7138 3662);
PAINT MONO (-7138 3662);
FORCEPROP 1 LASTPIN (-6950 3650) $PN 2
J 0
(-6988 3662);
DISPLAY 0.489362 (-6988 3662);
PAINT MONO (-6988 3662);
FORCEPROP 1 LAST VALUE 4.7K
J 0
(-6925 3650);
DISPLAY 0.489362 (-6925 3650);
PAINT SKYBLUE (-6925 3650);
FORCEPROP 1 LAST MATERIAL EMPTY
J 0
(-6950 3625);
DISPLAY 0.489362 (-6950 3625);
PAINT RED (-6950 3625);
FORCEPROP 1 LAST PACK_TYPE 0402LF
J 0
(-6800 3500);
DISPLAY 0.510638 (-6800 3500);
PAINT SKYBLUE (-6800 3500);
DISPLAY INVISIBLE (-6800 3500);
FORCEPROP 1 LAST TOLERANCE 5%
J 0
(-6925 3650);
DISPLAY 0.510638 (-6925 3650);
PAINT SKYBLUE (-6925 3650);
DISPLAY INVISIBLE (-6925 3650);
FORCEPROP 1 LAST WATTAGE 1/16W
J 2
(-7075 3500);
DISPLAY 0.510638 (-7075 3500);
PAINT SKYBLUE (-7075 3500);
DISPLAY INVISIBLE (-7075 3500);
FORCEPROP 2 LAST CDS_LIB pure_quanta
J 0
(-7050 3650);
DISPLAY INVISIBLE (-7050 3650);
FORCEPROP 1 LAST PATH I38
J 0
(-7100 3800);
DISPLAY 0.978723 (-7100 3800);
PAINT WHITE (-7100 3800);
DISPLAY INVISIBLE (-7100 3800);
FORCEPROP 1 LAST PART_NUMBER CS24702JB10
J 0
(-7100 3750);
DISPLAY 0.510638 (-7100 3750);
PAINT SKYBLUE (-7100 3750);
DISPLAY INVISIBLE (-7100 3750);
FORCEADD Q_RES..1
(-7050 3825);
FORCEPROP 1 LAST LOCATION R6061
J 0
(-7350 3825);
DISPLAY 0.489362 (-7350 3825);
PAINT SKYBLUE (-7350 3825);
FORCEPROP 0 LAST $SEC 1
J 0
(-7350 3875);
DISPLAY 0.680851 (-7350 3875);
PAINT MONO (-7350 3875);
DISPLAY INVISIBLE (-7350 3875);
FORCEPROP 0 LAST CDS_SEC 1
J 0
(-7350 3875);
DISPLAY 0.680851 (-7350 3875);
DISPLAY INVISIBLE (-7350 3875);
FORCEPROP 1 LASTPIN (-7150 3825) $PN 1
J 0
(-7138 3837);
DISPLAY 0.489362 (-7138 3837);
PAINT MONO (-7138 3837);
FORCEPROP 1 LASTPIN (-6950 3825) $PN 2
J 0
(-6988 3837);
DISPLAY 0.489362 (-6988 3837);
PAINT MONO (-6988 3837);
FORCEPROP 1 LAST MATERIAL EMPTY
J 0
(-6950 3800);
DISPLAY 0.489362 (-6950 3800);
PAINT RED (-6950 3800);
FORCEPROP 1 LAST VALUE 4.7K
J 0
(-6925 3825);
DISPLAY 0.489362 (-6925 3825);
PAINT SKYBLUE (-6925 3825);
FORCEPROP 2 LAST CDS_LIB pure_quanta
J 0
(-7050 3825);
DISPLAY INVISIBLE (-7050 3825);
FORCEPROP 1 LAST WATTAGE 1/16W
J 2
(-7075 3675);
DISPLAY 0.510638 (-7075 3675);
PAINT SKYBLUE (-7075 3675);
DISPLAY INVISIBLE (-7075 3675);
FORCEPROP 1 LAST TOLERANCE 5%
J 0
(-6925 3825);
DISPLAY 0.510638 (-6925 3825);
PAINT SKYBLUE (-6925 3825);
DISPLAY INVISIBLE (-6925 3825);
FORCEPROP 1 LAST PACK_TYPE 0402LF
J 0
(-6800 3675);
DISPLAY 0.510638 (-6800 3675);
PAINT SKYBLUE (-6800 3675);
DISPLAY INVISIBLE (-6800 3675);
FORCEPROP 1 LAST PATH I39
J 0
(-7100 3975);
DISPLAY 0.978723 (-7100 3975);
PAINT WHITE (-7100 3975);
DISPLAY INVISIBLE (-7100 3975);
FORCEPROP 1 LAST PART_NUMBER CS24702JB10
J 0
(-7100 3925);
DISPLAY 0.510638 (-7100 3925);
PAINT SKYBLUE (-7100 3925);
DISPLAY INVISIBLE (-7100 3925);
FORCEADD OFFPAGE..5
(-8225 3000);
FORCEPROP 2 LAST $XR1 80 
J 0
(-8570 3000);
DISPLAY 0.638298 (-8570 3000);
PAINT MONO (-8570 3000);
FORCEPROP 2 LAST $XR0 150 
J 0
(-8480 3000);
DISPLAY 0.638298 (-8480 3000);
PAINT MONO (-8480 3000);
FORCEPROP 2 LAST CDS_LIB standard
J 0
(-8225 3000);
DISPLAY INVISIBLE (-8225 3000);
FORCEPROP 1 LAST OFFPAGE TRUE
J 0
(-7900 2875);
DISPLAY 0.872340 (-7900 2875);
PAINT GREEN (-7900 2875);
DISPLAY INVISIBLE (-7900 2875);
FORCEPROP 1 LAST COMMENT_BODY TRUE
J 0
(-8125 2925);
DISPLAY 0.872340 (-8125 2925);
PAINT GREEN (-8125 2925);
DISPLAY INVISIBLE (-8125 2925);
FORCEPROP 2 LAST PATH I4
J 0
(-8500 3050);
DISPLAY 0.680851 (-8500 3050);
DISPLAY INVISIBLE (-8500 3050);
FORCEADD Q_RES..1
(-7050 3775);
FORCEPROP 1 LAST LOCATION R6062
J 0
(-7350 3775);
DISPLAY 0.489362 (-7350 3775);
PAINT SKYBLUE (-7350 3775);
FORCEPROP 0 LAST $SEC 1
J 0
(-7350 3825);
DISPLAY 0.680851 (-7350 3825);
PAINT MONO (-7350 3825);
DISPLAY INVISIBLE (-7350 3825);
FORCEPROP 0 LAST CDS_SEC 1
J 0
(-7350 3825);
DISPLAY 0.680851 (-7350 3825);
DISPLAY INVISIBLE (-7350 3825);
FORCEPROP 1 LASTPIN (-7150 3775) $PN 1
J 0
(-7138 3787);
DISPLAY 0.489362 (-7138 3787);
PAINT MONO (-7138 3787);
FORCEPROP 1 LASTPIN (-6950 3775) $PN 2
J 0
(-6988 3787);
DISPLAY 0.489362 (-6988 3787);
PAINT MONO (-6988 3787);
FORCEPROP 1 LAST MATERIAL EMPTY
J 0
(-6950 3750);
DISPLAY 0.489362 (-6950 3750);
PAINT RED (-6950 3750);
FORCEPROP 1 LAST VALUE 4.7K
J 0
(-6925 3775);
DISPLAY 0.489362 (-6925 3775);
PAINT SKYBLUE (-6925 3775);
FORCEPROP 2 LAST CDS_LIB pure_quanta
J 0
(-7050 3775);
DISPLAY INVISIBLE (-7050 3775);
FORCEPROP 1 LAST WATTAGE 1/16W
J 2
(-7075 3625);
DISPLAY 0.510638 (-7075 3625);
PAINT SKYBLUE (-7075 3625);
DISPLAY INVISIBLE (-7075 3625);
FORCEPROP 1 LAST TOLERANCE 5%
J 0
(-6925 3775);
DISPLAY 0.510638 (-6925 3775);
PAINT SKYBLUE (-6925 3775);
DISPLAY INVISIBLE (-6925 3775);
FORCEPROP 1 LAST PACK_TYPE 0402LF
J 0
(-6800 3625);
DISPLAY 0.510638 (-6800 3625);
PAINT SKYBLUE (-6800 3625);
DISPLAY INVISIBLE (-6800 3625);
FORCEPROP 1 LAST PATH I40
J 0
(-7100 3925);
DISPLAY 0.978723 (-7100 3925);
PAINT WHITE (-7100 3925);
DISPLAY INVISIBLE (-7100 3925);
FORCEPROP 1 LAST PART_NUMBER CS24702JB10
J 0
(-7100 3875);
DISPLAY 0.510638 (-7100 3875);
PAINT SKYBLUE (-7100 3875);
DISPLAY INVISIBLE (-7100 3875);
FORCEADD Q_RES..1
(-7050 3950);
FORCEPROP 1 LAST LOCATION R757
J 0
(-7350 3950);
DISPLAY 0.489362 (-7350 3950);
PAINT SKYBLUE (-7350 3950);
FORCEPROP 0 LAST $SEC 1
J 0
(-7350 4000);
DISPLAY 0.680851 (-7350 4000);
PAINT MONO (-7350 4000);
DISPLAY INVISIBLE (-7350 4000);
FORCEPROP 0 LAST CDS_SEC 1
J 0
(-7350 4000);
DISPLAY 0.680851 (-7350 4000);
DISPLAY INVISIBLE (-7350 4000);
FORCEPROP 1 LASTPIN (-7150 3950) $PN 1
J 0
(-7138 3962);
DISPLAY 0.489362 (-7138 3962);
PAINT MONO (-7138 3962);
FORCEPROP 1 LASTPIN (-6950 3950) $PN 2
J 0
(-6988 3962);
DISPLAY 0.489362 (-6988 3962);
PAINT MONO (-6988 3962);
FORCEPROP 1 LAST MATERIAL EMPTY
J 0
(-6950 3925);
DISPLAY 0.489362 (-6950 3925);
PAINT RED (-6950 3925);
FORCEPROP 1 LAST VALUE 4.7K
J 0
(-6925 3950);
DISPLAY 0.489362 (-6925 3950);
PAINT SKYBLUE (-6925 3950);
FORCEPROP 2 LAST CDS_LIB pure_quanta
J 0
(-7050 3950);
DISPLAY INVISIBLE (-7050 3950);
FORCEPROP 1 LAST WATTAGE 1/16W
J 2
(-7075 3800);
DISPLAY 0.510638 (-7075 3800);
PAINT SKYBLUE (-7075 3800);
DISPLAY INVISIBLE (-7075 3800);
FORCEPROP 1 LAST TOLERANCE 5%
J 0
(-6925 3950);
DISPLAY 0.510638 (-6925 3950);
PAINT SKYBLUE (-6925 3950);
DISPLAY INVISIBLE (-6925 3950);
FORCEPROP 1 LAST PACK_TYPE 0402LF
J 0
(-6800 3800);
DISPLAY 0.510638 (-6800 3800);
PAINT SKYBLUE (-6800 3800);
DISPLAY INVISIBLE (-6800 3800);
FORCEPROP 1 LAST PATH I41
J 0
(-7100 4100);
DISPLAY 0.978723 (-7100 4100);
PAINT WHITE (-7100 4100);
DISPLAY INVISIBLE (-7100 4100);
FORCEPROP 1 LAST PART_NUMBER CS24702JB10
J 0
(-7100 4050);
DISPLAY 0.510638 (-7100 4050);
PAINT SKYBLUE (-7100 4050);
DISPLAY INVISIBLE (-7100 4050);
FORCEADD OFFPAGE..5
(-8225 3075);
FORCEPROP 2 LAST $XR0 80 
J 0
(-8449 3075);
DISPLAY 0.638298 (-8449 3075);
PAINT MONO (-8449 3075);
FORCEPROP 2 LAST CDS_LIB standard
J 0
(-8225 3075);
DISPLAY INVISIBLE (-8225 3075);
FORCEPROP 1 LAST OFFPAGE TRUE
J 0
(-7900 2950);
DISPLAY 0.872340 (-7900 2950);
PAINT GREEN (-7900 2950);
DISPLAY INVISIBLE (-7900 2950);
FORCEPROP 1 LAST COMMENT_BODY TRUE
J 0
(-8125 3000);
DISPLAY 0.872340 (-8125 3000);
PAINT GREEN (-8125 3000);
DISPLAY INVISIBLE (-8125 3000);
FORCEPROP 2 LAST PATH I5
J 0
(-8475 3125);
DISPLAY 0.680851 (-8475 3125);
DISPLAY INVISIBLE (-8475 3125);
FORCEADD Q_RES..1
(-7050 4325);
FORCEPROP 1 LAST LOCATION R993
J 0
(-7350 4325);
DISPLAY 0.489362 (-7350 4325);
PAINT SKYBLUE (-7350 4325);
FORCEPROP 0 LAST $SEC 1
J 0
(-7350 4375);
DISPLAY 0.680851 (-7350 4375);
PAINT MONO (-7350 4375);
DISPLAY INVISIBLE (-7350 4375);
FORCEPROP 0 LAST CDS_SEC 1
J 0
(-7350 4375);
DISPLAY 0.680851 (-7350 4375);
DISPLAY INVISIBLE (-7350 4375);
FORCEPROP 1 LASTPIN (-7150 4325) $PN 1
J 0
(-7138 4337);
DISPLAY 0.489362 (-7138 4337);
PAINT MONO (-7138 4337);
FORCEPROP 1 LASTPIN (-6950 4325) $PN 2
J 0
(-6988 4337);
DISPLAY 0.489362 (-6988 4337);
PAINT MONO (-6988 4337);
FORCEPROP 1 LAST VALUE 1K
J 0
(-6925 4325);
DISPLAY 0.489362 (-6925 4325);
PAINT SKYBLUE (-6925 4325);
FORCEPROP 1 LAST TOLERANCE 1%
J 0
(-6925 4325);
DISPLAY 0.510638 (-6925 4325);
PAINT SKYBLUE (-6925 4325);
DISPLAY INVISIBLE (-6925 4325);
FORCEPROP 2 LAST CDS_LIB pure_quanta
J 0
(-7050 4325);
DISPLAY INVISIBLE (-7050 4325);
FORCEPROP 1 LAST WATTAGE 1/16W
J 2
(-7075 4175);
DISPLAY 0.510638 (-7075 4175);
PAINT SKYBLUE (-7075 4175);
DISPLAY INVISIBLE (-7075 4175);
FORCEPROP 1 LAST MATERIAL CHIP
J 0
(-6950 4300);
DISPLAY 0.489362 (-6950 4300);
PAINT SKYBLUE (-6950 4300);
DISPLAY INVISIBLE (-6950 4300);
FORCEPROP 1 LAST PACK_TYPE 0402LF
J 0
(-6800 4175);
DISPLAY 0.510638 (-6800 4175);
PAINT SKYBLUE (-6800 4175);
DISPLAY INVISIBLE (-6800 4175);
FORCEPROP 1 LAST PATH I53
J 0
(-7100 4475);
DISPLAY 0.978723 (-7100 4475);
PAINT WHITE (-7100 4475);
DISPLAY INVISIBLE (-7100 4475);
FORCEPROP 1 LAST PART_NUMBER CS21002FB06
J 0
(-7100 4425);
DISPLAY 0.510638 (-7100 4425);
PAINT SKYBLUE (-7100 4425);
DISPLAY INVISIBLE (-7100 4425);
FORCEADD Q_RES..1
(-7050 4200);
FORCEPROP 1 LAST LOCATION R1314
J 0
(-7350 4200);
DISPLAY 0.489362 (-7350 4200);
PAINT SKYBLUE (-7350 4200);
FORCEPROP 0 LAST $SEC 1
J 0
(-7350 4250);
DISPLAY 0.680851 (-7350 4250);
PAINT MONO (-7350 4250);
DISPLAY INVISIBLE (-7350 4250);
FORCEPROP 0 LAST CDS_SEC 1
J 0
(-7350 4250);
DISPLAY 0.680851 (-7350 4250);
DISPLAY INVISIBLE (-7350 4250);
FORCEPROP 1 LASTPIN (-7150 4200) $PN 1
J 0
(-7138 4212);
DISPLAY 0.489362 (-7138 4212);
PAINT MONO (-7138 4212);
FORCEPROP 1 LASTPIN (-6950 4200) $PN 2
J 0
(-6988 4212);
DISPLAY 0.489362 (-6988 4212);
PAINT MONO (-6988 4212);
FORCEPROP 1 LAST VALUE 4.7K
J 0
(-6925 4200);
DISPLAY 0.489362 (-6925 4200);
PAINT SKYBLUE (-6925 4200);
FORCEPROP 1 LAST MATERIAL EMPTY
J 0
(-6950 4175);
DISPLAY 0.489362 (-6950 4175);
PAINT RED (-6950 4175);
FORCEPROP 2 LAST CDS_LIB pure_quanta
J 0
(-7050 4200);
DISPLAY INVISIBLE (-7050 4200);
FORCEPROP 1 LAST PACK_TYPE 0402LF
J 0
(-6800 4050);
DISPLAY 0.510638 (-6800 4050);
PAINT SKYBLUE (-6800 4050);
DISPLAY INVISIBLE (-6800 4050);
FORCEPROP 1 LAST TOLERANCE 5%
J 0
(-6925 4200);
DISPLAY 0.510638 (-6925 4200);
PAINT SKYBLUE (-6925 4200);
DISPLAY INVISIBLE (-6925 4200);
FORCEPROP 1 LAST WATTAGE 1/16W
J 2
(-7075 4050);
DISPLAY 0.510638 (-7075 4050);
PAINT SKYBLUE (-7075 4050);
DISPLAY INVISIBLE (-7075 4050);
FORCEPROP 1 LAST PATH I54
J 0
(-7100 4350);
DISPLAY 0.978723 (-7100 4350);
PAINT WHITE (-7100 4350);
DISPLAY INVISIBLE (-7100 4350);
FORCEPROP 1 LAST PART_NUMBER CS24702JB10
J 0
(-7100 4300);
DISPLAY 0.510638 (-7100 4300);
PAINT SKYBLUE (-7100 4300);
DISPLAY INVISIBLE (-7100 4300);
FORCEADD Q_RES..1
(-7050 5250);
FORCEPROP 1 LAST LOCATION R1527
J 0
(-7350 5250);
DISPLAY 0.489362 (-7350 5250);
PAINT SKYBLUE (-7350 5250);
FORCEPROP 0 LAST $SEC 1
J 0
(-6925 5275);
DISPLAY 0.680851 (-6925 5275);
PAINT MONO (-6925 5275);
DISPLAY INVISIBLE (-6925 5275);
FORCEPROP 0 LAST CDS_SEC 1
J 0
(-6925 5275);
DISPLAY 0.680851 (-6925 5275);
DISPLAY INVISIBLE (-6925 5275);
FORCEPROP 1 LASTPIN (-7150 5250) $PN 1
J 0
(-7138 5262);
DISPLAY 0.489362 (-7138 5262);
PAINT MONO (-7138 5262);
FORCEPROP 1 LASTPIN (-6950 5250) $PN 2
J 0
(-6988 5262);
DISPLAY 0.489362 (-6988 5262);
PAINT MONO (-6988 5262);
FORCEPROP 1 LAST VALUE 1K
J 0
(-6925 5250);
DISPLAY 0.489362 (-6925 5250);
PAINT SKYBLUE (-6925 5250);
FORCEPROP 1 LAST TOLERANCE 1%
J 0
(-6925 5250);
DISPLAY 0.510638 (-6925 5250);
PAINT SKYBLUE (-6925 5250);
DISPLAY INVISIBLE (-6925 5250);
FORCEPROP 2 LAST CDS_LIB pure_quanta
J 0
(-7050 5250);
DISPLAY INVISIBLE (-7050 5250);
FORCEPROP 1 LAST WATTAGE 1/16W
J 2
(-7075 5100);
DISPLAY 0.510638 (-7075 5100);
PAINT SKYBLUE (-7075 5100);
DISPLAY INVISIBLE (-7075 5100);
FORCEPROP 1 LAST MATERIAL CHIP
J 0
(-6950 5225);
DISPLAY 0.489362 (-6950 5225);
PAINT SKYBLUE (-6950 5225);
DISPLAY INVISIBLE (-6950 5225);
FORCEPROP 1 LAST PACK_TYPE 0402LF
J 0
(-6800 5100);
DISPLAY 0.510638 (-6800 5100);
PAINT SKYBLUE (-6800 5100);
DISPLAY INVISIBLE (-6800 5100);
FORCEPROP 1 LAST PATH I56
J 0
(-7100 5400);
DISPLAY 0.978723 (-7100 5400);
PAINT WHITE (-7100 5400);
DISPLAY INVISIBLE (-7100 5400);
FORCEPROP 1 LAST PART_NUMBER CS21002FB06
J 0
(-7100 5350);
DISPLAY 0.510638 (-7100 5350);
PAINT SKYBLUE (-7100 5350);
DISPLAY INVISIBLE (-7100 5350);
FORCEADD Q_RES..1
(-7050 5375);
FORCEPROP 1 LAST LOCATION R1189
J 0
(-7350 5375);
DISPLAY 0.489362 (-7350 5375);
PAINT SKYBLUE (-7350 5375);
FORCEPROP 0 LAST $SEC 1
J 0
(-7350 5425);
DISPLAY 0.680851 (-7350 5425);
PAINT MONO (-7350 5425);
DISPLAY INVISIBLE (-7350 5425);
FORCEPROP 0 LAST CDS_SEC 1
J 0
(-7350 5425);
DISPLAY 0.680851 (-7350 5425);
DISPLAY INVISIBLE (-7350 5425);
FORCEPROP 1 LASTPIN (-7150 5375) $PN 1
J 0
(-7138 5387);
DISPLAY 0.489362 (-7138 5387);
PAINT MONO (-7138 5387);
FORCEPROP 1 LASTPIN (-6950 5375) $PN 2
J 0
(-6988 5387);
DISPLAY 0.489362 (-6988 5387);
PAINT MONO (-6988 5387);
FORCEPROP 1 LAST VALUE 1K
J 0
(-6925 5375);
DISPLAY 0.489362 (-6925 5375);
PAINT SKYBLUE (-6925 5375);
FORCEPROP 1 LAST TOLERANCE 1%
J 0
(-6925 5375);
DISPLAY 0.510638 (-6925 5375);
PAINT SKYBLUE (-6925 5375);
DISPLAY INVISIBLE (-6925 5375);
FORCEPROP 2 LAST CDS_LIB pure_quanta
J 0
(-7050 5375);
DISPLAY INVISIBLE (-7050 5375);
FORCEPROP 1 LAST WATTAGE 1/16W
J 2
(-7075 5225);
DISPLAY 0.510638 (-7075 5225);
PAINT SKYBLUE (-7075 5225);
DISPLAY INVISIBLE (-7075 5225);
FORCEPROP 1 LAST MATERIAL CHIP
J 0
(-6950 5350);
DISPLAY 0.489362 (-6950 5350);
PAINT SKYBLUE (-6950 5350);
DISPLAY INVISIBLE (-6950 5350);
FORCEPROP 1 LAST PACK_TYPE 0402LF
J 0
(-6800 5225);
DISPLAY 0.510638 (-6800 5225);
PAINT SKYBLUE (-6800 5225);
DISPLAY INVISIBLE (-6800 5225);
FORCEPROP 1 LAST PATH I57
J 0
(-7100 5525);
DISPLAY 0.978723 (-7100 5525);
PAINT WHITE (-7100 5525);
DISPLAY INVISIBLE (-7100 5525);
FORCEPROP 1 LAST PART_NUMBER CS21002FB06
J 0
(-7100 5475);
DISPLAY 0.510638 (-7100 5475);
PAINT SKYBLUE (-7100 5475);
DISPLAY INVISIBLE (-7100 5475);
FORCEADD Q_RES..1
(-7050 5325);
FORCEPROP 1 LAST LOCATION R1190
J 0
(-7350 5325);
DISPLAY 0.489362 (-7350 5325);
PAINT SKYBLUE (-7350 5325);
FORCEPROP 0 LAST $SEC 1
J 0
(-7350 5375);
DISPLAY 0.680851 (-7350 5375);
PAINT MONO (-7350 5375);
DISPLAY INVISIBLE (-7350 5375);
FORCEPROP 0 LAST CDS_SEC 1
J 0
(-7350 5375);
DISPLAY 0.680851 (-7350 5375);
DISPLAY INVISIBLE (-7350 5375);
FORCEPROP 1 LASTPIN (-7150 5325) $PN 1
J 0
(-7138 5337);
DISPLAY 0.489362 (-7138 5337);
PAINT MONO (-7138 5337);
FORCEPROP 1 LASTPIN (-6950 5325) $PN 2
J 0
(-6988 5337);
DISPLAY 0.489362 (-6988 5337);
PAINT MONO (-6988 5337);
FORCEPROP 1 LAST VALUE 1K
J 0
(-6925 5325);
DISPLAY 0.489362 (-6925 5325);
PAINT SKYBLUE (-6925 5325);
FORCEPROP 1 LAST TOLERANCE 1%
J 0
(-6925 5325);
DISPLAY 0.510638 (-6925 5325);
PAINT SKYBLUE (-6925 5325);
DISPLAY INVISIBLE (-6925 5325);
FORCEPROP 2 LAST CDS_LIB pure_quanta
J 0
(-7050 5325);
DISPLAY INVISIBLE (-7050 5325);
FORCEPROP 1 LAST WATTAGE 1/16W
J 2
(-7075 5175);
DISPLAY 0.510638 (-7075 5175);
PAINT SKYBLUE (-7075 5175);
DISPLAY INVISIBLE (-7075 5175);
FORCEPROP 1 LAST MATERIAL CHIP
J 0
(-6950 5300);
DISPLAY 0.489362 (-6950 5300);
PAINT SKYBLUE (-6950 5300);
DISPLAY INVISIBLE (-6950 5300);
FORCEPROP 1 LAST PACK_TYPE 0402LF
J 0
(-6800 5175);
DISPLAY 0.510638 (-6800 5175);
PAINT SKYBLUE (-6800 5175);
DISPLAY INVISIBLE (-6800 5175);
FORCEPROP 1 LAST PATH I58
J 0
(-7100 5475);
DISPLAY 0.978723 (-7100 5475);
PAINT WHITE (-7100 5475);
DISPLAY INVISIBLE (-7100 5475);
FORCEPROP 1 LAST PART_NUMBER CS21002FB06
J 0
(-7100 5425);
DISPLAY 0.510638 (-7100 5425);
PAINT SKYBLUE (-7100 5425);
DISPLAY INVISIBLE (-7100 5425);
FORCEADD Q_RES..1
(-7050 5475);
FORCEPROP 1 LAST LOCATION R1187
J 0
(-7350 5475);
DISPLAY 0.489362 (-7350 5475);
PAINT SKYBLUE (-7350 5475);
FORCEPROP 0 LAST $SEC 1
J 0
(-7350 5525);
DISPLAY 0.680851 (-7350 5525);
PAINT MONO (-7350 5525);
DISPLAY INVISIBLE (-7350 5525);
FORCEPROP 0 LAST CDS_SEC 1
J 0
(-7350 5525);
DISPLAY 0.680851 (-7350 5525);
DISPLAY INVISIBLE (-7350 5525);
FORCEPROP 1 LASTPIN (-7150 5475) $PN 1
J 0
(-7138 5487);
DISPLAY 0.489362 (-7138 5487);
PAINT MONO (-7138 5487);
FORCEPROP 1 LASTPIN (-6950 5475) $PN 2
J 0
(-6988 5487);
DISPLAY 0.489362 (-6988 5487);
PAINT MONO (-6988 5487);
FORCEPROP 1 LAST VALUE 1K
J 0
(-6925 5475);
DISPLAY 0.489362 (-6925 5475);
PAINT SKYBLUE (-6925 5475);
FORCEPROP 1 LAST TOLERANCE 1%
J 0
(-6925 5475);
DISPLAY 0.510638 (-6925 5475);
PAINT SKYBLUE (-6925 5475);
DISPLAY INVISIBLE (-6925 5475);
FORCEPROP 2 LAST CDS_LIB pure_quanta
J 0
(-7050 5475);
DISPLAY INVISIBLE (-7050 5475);
FORCEPROP 1 LAST WATTAGE 1/16W
J 2
(-7075 5325);
DISPLAY 0.510638 (-7075 5325);
PAINT SKYBLUE (-7075 5325);
DISPLAY INVISIBLE (-7075 5325);
FORCEPROP 1 LAST MATERIAL CHIP
J 0
(-6950 5450);
DISPLAY 0.489362 (-6950 5450);
PAINT SKYBLUE (-6950 5450);
DISPLAY INVISIBLE (-6950 5450);
FORCEPROP 1 LAST PACK_TYPE 0402LF
J 0
(-6800 5325);
DISPLAY 0.510638 (-6800 5325);
PAINT SKYBLUE (-6800 5325);
DISPLAY INVISIBLE (-6800 5325);
FORCEPROP 1 LAST PATH I59
J 0
(-7100 5625);
DISPLAY 0.978723 (-7100 5625);
PAINT WHITE (-7100 5625);
DISPLAY INVISIBLE (-7100 5625);
FORCEPROP 1 LAST PART_NUMBER CS21002FB06
J 0
(-7100 5575);
DISPLAY 0.510638 (-7100 5575);
PAINT SKYBLUE (-7100 5575);
DISPLAY INVISIBLE (-7100 5575);
FORCEADD OFFPAGE..5
(-8225 3125);
FORCEPROP 2 LAST $XR0 80 
J 0
(-8449 3125);
DISPLAY 0.638298 (-8449 3125);
PAINT MONO (-8449 3125);
FORCEPROP 2 LAST CDS_LIB standard
J 0
(-8225 3125);
DISPLAY INVISIBLE (-8225 3125);
FORCEPROP 1 LAST OFFPAGE TRUE
J 0
(-7900 3000);
DISPLAY 0.872340 (-7900 3000);
PAINT GREEN (-7900 3000);
DISPLAY INVISIBLE (-7900 3000);
FORCEPROP 1 LAST COMMENT_BODY TRUE
J 0
(-8125 3050);
DISPLAY 0.872340 (-8125 3050);
PAINT GREEN (-8125 3050);
DISPLAY INVISIBLE (-8125 3050);
FORCEPROP 2 LAST PATH I6
J 0
(-8475 3175);
DISPLAY 0.680851 (-8475 3175);
DISPLAY INVISIBLE (-8475 3175);
FORCEADD Q_RES..1
(-7050 5525);
FORCEPROP 1 LAST LOCATION R1186
J 0
(-7350 5525);
DISPLAY 0.489362 (-7350 5525);
PAINT SKYBLUE (-7350 5525);
FORCEPROP 0 LAST $SEC 1
J 0
(-7350 5575);
DISPLAY 0.680851 (-7350 5575);
PAINT MONO (-7350 5575);
DISPLAY INVISIBLE (-7350 5575);
FORCEPROP 0 LAST CDS_SEC 1
J 0
(-7350 5575);
DISPLAY 0.680851 (-7350 5575);
DISPLAY INVISIBLE (-7350 5575);
FORCEPROP 1 LASTPIN (-7150 5525) $PN 1
J 0
(-7138 5537);
DISPLAY 0.489362 (-7138 5537);
PAINT MONO (-7138 5537);
FORCEPROP 1 LASTPIN (-6950 5525) $PN 2
J 0
(-6988 5537);
DISPLAY 0.489362 (-6988 5537);
PAINT MONO (-6988 5537);
FORCEPROP 1 LAST VALUE 1K
J 0
(-6925 5525);
DISPLAY 0.489362 (-6925 5525);
PAINT SKYBLUE (-6925 5525);
FORCEPROP 1 LAST TOLERANCE 1%
J 0
(-6925 5525);
DISPLAY 0.510638 (-6925 5525);
PAINT SKYBLUE (-6925 5525);
DISPLAY INVISIBLE (-6925 5525);
FORCEPROP 2 LAST CDS_LIB pure_quanta
J 0
(-7050 5525);
DISPLAY INVISIBLE (-7050 5525);
FORCEPROP 1 LAST WATTAGE 1/16W
J 2
(-7075 5375);
DISPLAY 0.510638 (-7075 5375);
PAINT SKYBLUE (-7075 5375);
DISPLAY INVISIBLE (-7075 5375);
FORCEPROP 1 LAST MATERIAL CHIP
J 0
(-6950 5500);
DISPLAY 0.489362 (-6950 5500);
PAINT SKYBLUE (-6950 5500);
DISPLAY INVISIBLE (-6950 5500);
FORCEPROP 1 LAST PACK_TYPE 0402LF
J 0
(-6800 5375);
DISPLAY 0.510638 (-6800 5375);
PAINT SKYBLUE (-6800 5375);
DISPLAY INVISIBLE (-6800 5375);
FORCEPROP 1 LAST PATH I60
J 0
(-7100 5675);
DISPLAY 0.978723 (-7100 5675);
PAINT WHITE (-7100 5675);
DISPLAY INVISIBLE (-7100 5675);
FORCEPROP 1 LAST PART_NUMBER CS21002FB06
J 0
(-7100 5625);
DISPLAY 0.510638 (-7100 5625);
PAINT SKYBLUE (-7100 5625);
DISPLAY INVISIBLE (-7100 5625);
FORCEADD Q_RES..1
(-7050 5425);
FORCEPROP 1 LAST LOCATION R1188
J 0
(-7350 5425);
DISPLAY 0.489362 (-7350 5425);
PAINT SKYBLUE (-7350 5425);
FORCEPROP 0 LAST $SEC 1
J 0
(-7350 5475);
DISPLAY 0.680851 (-7350 5475);
PAINT MONO (-7350 5475);
DISPLAY INVISIBLE (-7350 5475);
FORCEPROP 0 LAST CDS_SEC 1
J 0
(-7350 5475);
DISPLAY 0.680851 (-7350 5475);
DISPLAY INVISIBLE (-7350 5475);
FORCEPROP 1 LASTPIN (-7150 5425) $PN 1
J 0
(-7138 5437);
DISPLAY 0.489362 (-7138 5437);
PAINT MONO (-7138 5437);
FORCEPROP 1 LASTPIN (-6950 5425) $PN 2
J 0
(-6988 5437);
DISPLAY 0.489362 (-6988 5437);
PAINT MONO (-6988 5437);
FORCEPROP 1 LAST VALUE 1K
J 0
(-6925 5425);
DISPLAY 0.489362 (-6925 5425);
PAINT SKYBLUE (-6925 5425);
FORCEPROP 1 LAST TOLERANCE 1%
J 0
(-6925 5425);
DISPLAY 0.510638 (-6925 5425);
PAINT SKYBLUE (-6925 5425);
DISPLAY INVISIBLE (-6925 5425);
FORCEPROP 2 LAST CDS_LIB pure_quanta
J 0
(-7050 5425);
DISPLAY INVISIBLE (-7050 5425);
FORCEPROP 1 LAST WATTAGE 1/16W
J 2
(-7075 5275);
DISPLAY 0.510638 (-7075 5275);
PAINT SKYBLUE (-7075 5275);
DISPLAY INVISIBLE (-7075 5275);
FORCEPROP 1 LAST MATERIAL CHIP
J 0
(-6950 5400);
DISPLAY 0.489362 (-6950 5400);
PAINT SKYBLUE (-6950 5400);
DISPLAY INVISIBLE (-6950 5400);
FORCEPROP 1 LAST PACK_TYPE 0402LF
J 0
(-6800 5275);
DISPLAY 0.510638 (-6800 5275);
PAINT SKYBLUE (-6800 5275);
DISPLAY INVISIBLE (-6800 5275);
FORCEPROP 1 LAST PATH I61
J 0
(-7100 5575);
DISPLAY 0.978723 (-7100 5575);
PAINT WHITE (-7100 5575);
DISPLAY INVISIBLE (-7100 5575);
FORCEPROP 1 LAST PART_NUMBER CS21002FB06
J 0
(-7100 5525);
DISPLAY 0.510638 (-7100 5525);
PAINT SKYBLUE (-7100 5525);
DISPLAY INVISIBLE (-7100 5525);
FORCEADD Q_RES..1
(-7050 5575);
FORCEPROP 1 LAST LOCATION R1185
J 0
(-7350 5575);
DISPLAY 0.489362 (-7350 5575);
PAINT SKYBLUE (-7350 5575);
FORCEPROP 0 LAST $SEC 1
J 0
(-7350 5625);
DISPLAY 0.680851 (-7350 5625);
PAINT MONO (-7350 5625);
DISPLAY INVISIBLE (-7350 5625);
FORCEPROP 0 LAST CDS_SEC 1
J 0
(-7350 5625);
DISPLAY 0.680851 (-7350 5625);
DISPLAY INVISIBLE (-7350 5625);
FORCEPROP 1 LASTPIN (-7150 5575) $PN 1
J 0
(-7138 5587);
DISPLAY 0.489362 (-7138 5587);
PAINT MONO (-7138 5587);
FORCEPROP 1 LASTPIN (-6950 5575) $PN 2
J 0
(-6988 5587);
DISPLAY 0.489362 (-6988 5587);
PAINT MONO (-6988 5587);
FORCEPROP 1 LAST VALUE 1K
J 0
(-6925 5575);
DISPLAY 0.489362 (-6925 5575);
PAINT SKYBLUE (-6925 5575);
FORCEPROP 1 LAST TOLERANCE 1%
J 0
(-6925 5575);
DISPLAY 0.510638 (-6925 5575);
PAINT SKYBLUE (-6925 5575);
DISPLAY INVISIBLE (-6925 5575);
FORCEPROP 2 LAST CDS_LIB pure_quanta
J 0
(-7050 5575);
DISPLAY INVISIBLE (-7050 5575);
FORCEPROP 1 LAST WATTAGE 1/16W
J 2
(-7075 5425);
DISPLAY 0.510638 (-7075 5425);
PAINT SKYBLUE (-7075 5425);
DISPLAY INVISIBLE (-7075 5425);
FORCEPROP 1 LAST MATERIAL CHIP
J 0
(-6950 5550);
DISPLAY 0.489362 (-6950 5550);
PAINT SKYBLUE (-6950 5550);
DISPLAY INVISIBLE (-6950 5550);
FORCEPROP 1 LAST PACK_TYPE 0402LF
J 0
(-6800 5425);
DISPLAY 0.510638 (-6800 5425);
PAINT SKYBLUE (-6800 5425);
DISPLAY INVISIBLE (-6800 5425);
FORCEPROP 1 LAST PATH I62
J 0
(-7100 5725);
DISPLAY 0.978723 (-7100 5725);
PAINT WHITE (-7100 5725);
DISPLAY INVISIBLE (-7100 5725);
FORCEPROP 1 LAST PART_NUMBER CS21002FB06
J 0
(-7100 5675);
DISPLAY 0.510638 (-7100 5675);
PAINT SKYBLUE (-7100 5675);
DISPLAY INVISIBLE (-7100 5675);
FORCEADD VCC_CORE..1
(-6800 5650);
FORCEPROP 3 LASTPIN (-6800 5600) SIG_NAME P3V3_AUX\g
J 0
(-6790 5610);
DISPLAY 0.659574 (-6790 5610);
PAINT MONO (-6790 5610);
DISPLAY INVISIBLE (-6790 5610);
FORCEPROP 1 LAST HDL_POWER P3V3_AUX
J 1
(-6800 5700);
DISPLAY 0.489362 (-6800 5700);
PAINT GREEN (-6800 5700);
FORCEPROP 2 LAST CDS_LIB pure_quanta_power
J 0
(-6800 5650);
DISPLAY INVISIBLE (-6800 5650);
FORCEPROP 1 LAST PATH I63
J 0
(-6750 5675);
DISPLAY 0.872340 (-6750 5675);
PAINT AQUA (-6750 5675);
DISPLAY INVISIBLE (-6750 5675);
FORCEADD Q_RES..1
(-7050 5750);
FORCEPROP 1 LAST LOCATION R654
J 0
(-7275 5750);
DISPLAY 0.489362 (-7275 5750);
PAINT SKYBLUE (-7275 5750);
FORCEPROP 2 LAST $SEC 1
J 0
(-7100 5950);
DISPLAY 0.680851 (-7100 5950);
PAINT MONO (-7100 5950);
DISPLAY INVISIBLE (-7100 5950);
FORCEPROP 2 LAST CDS_SEC 1
J 0
(-7100 5950);
DISPLAY 0.680851 (-7100 5950);
DISPLAY INVISIBLE (-7100 5950);
FORCEPROP 1 LASTPIN (-7150 5750) $PN 1
J 0
(-7138 5762);
DISPLAY 0.489362 (-7138 5762);
PAINT MONO (-7138 5762);
FORCEPROP 1 LASTPIN (-6950 5750) $PN 2
J 0
(-6988 5762);
DISPLAY 0.489362 (-6988 5762);
PAINT MONO (-6988 5762);
FORCEPROP 1 LAST VALUE 4.7K
J 0
(-6925 5750);
DISPLAY 0.489362 (-6925 5750);
PAINT SKYBLUE (-6925 5750);
FORCEPROP 1 LAST PACK_TYPE 0402LF
J 0
(-6800 5600);
DISPLAY 0.510638 (-6800 5600);
PAINT SKYBLUE (-6800 5600);
DISPLAY INVISIBLE (-6800 5600);
FORCEPROP 2 LAST CDS_LIB pure_quanta
J 0
(-7050 5750);
DISPLAY INVISIBLE (-7050 5750);
FORCEPROP 1 LAST WATTAGE 1/16W
J 2
(-7075 5600);
DISPLAY 0.510638 (-7075 5600);
PAINT SKYBLUE (-7075 5600);
DISPLAY INVISIBLE (-7075 5600);
FORCEPROP 1 LAST MATERIAL CHIP
J 0
(-6950 5725);
DISPLAY 0.489362 (-6950 5725);
PAINT SKYBLUE (-6950 5725);
DISPLAY INVISIBLE (-6950 5725);
FORCEPROP 1 LAST TOLERANCE 5%
J 0
(-6925 5750);
DISPLAY 0.510638 (-6925 5750);
PAINT SKYBLUE (-6925 5750);
DISPLAY INVISIBLE (-6925 5750);
FORCEPROP 1 LAST PATH I64
J 0
(-7100 5900);
DISPLAY 0.978723 (-7100 5900);
PAINT WHITE (-7100 5900);
DISPLAY INVISIBLE (-7100 5900);
FORCEPROP 1 LAST PART_NUMBER CS24702JB10
J 0
(-7100 5850);
DISPLAY 0.510638 (-7100 5850);
PAINT SKYBLUE (-7100 5850);
DISPLAY INVISIBLE (-7100 5850);
FORCEADD OFFPAGE..5
(-6100 5275);
FORCEPROP 2 LAST $XR1 29 
J 0
(-6414 5275);
DISPLAY 0.638298 (-6414 5275);
PAINT MONO (-6414 5275);
FORCEPROP 2 LAST $XR0 81 
J 0
(-6324 5275);
DISPLAY 0.638298 (-6324 5275);
PAINT MONO (-6324 5275);
FORCEPROP 2 LAST CDS_LIB standard
J 0
(-6100 5275);
DISPLAY INVISIBLE (-6100 5275);
FORCEPROP 1 LAST OFFPAGE TRUE
J 0
(-5775 5150);
DISPLAY 0.872340 (-5775 5150);
PAINT GREEN (-5775 5150);
DISPLAY INVISIBLE (-5775 5150);
FORCEPROP 1 LAST COMMENT_BODY TRUE
J 0
(-6000 5200);
DISPLAY 0.872340 (-6000 5200);
PAINT GREEN (-6000 5200);
DISPLAY INVISIBLE (-6000 5200);
FORCEPROP 2 LAST PATH I65
J 0
(-6300 5325);
DISPLAY 0.680851 (-6300 5325);
DISPLAY INVISIBLE (-6300 5325);
FORCEADD OFFPAGE..5
(-6100 5400);
FORCEPROP 2 LAST $XR1 27 
J 0
(-6414 5400);
DISPLAY 0.638298 (-6414 5400);
PAINT MONO (-6414 5400);
FORCEPROP 2 LAST $XR0 81 
J 0
(-6324 5400);
DISPLAY 0.638298 (-6324 5400);
PAINT MONO (-6324 5400);
FORCEPROP 2 LAST CDS_LIB standard
J 0
(-6100 5400);
DISPLAY INVISIBLE (-6100 5400);
FORCEPROP 1 LAST OFFPAGE TRUE
J 0
(-5775 5275);
DISPLAY 0.872340 (-5775 5275);
PAINT GREEN (-5775 5275);
DISPLAY INVISIBLE (-5775 5275);
FORCEPROP 1 LAST COMMENT_BODY TRUE
J 0
(-6000 5325);
DISPLAY 0.872340 (-6000 5325);
PAINT GREEN (-6000 5325);
DISPLAY INVISIBLE (-6000 5325);
FORCEPROP 2 LAST PATH I66
J 0
(-6300 5450);
DISPLAY 0.680851 (-6300 5450);
DISPLAY INVISIBLE (-6300 5450);
FORCEADD OFFPAGE..5
(-6100 5350);
FORCEPROP 2 LAST $XR1 27 
J 0
(-6414 5350);
DISPLAY 0.638298 (-6414 5350);
PAINT MONO (-6414 5350);
FORCEPROP 2 LAST $XR0 81 
J 0
(-6324 5350);
DISPLAY 0.638298 (-6324 5350);
PAINT MONO (-6324 5350);
FORCEPROP 2 LAST CDS_LIB standard
J 0
(-6100 5350);
DISPLAY INVISIBLE (-6100 5350);
FORCEPROP 1 LAST OFFPAGE TRUE
J 0
(-5775 5225);
DISPLAY 0.872340 (-5775 5225);
PAINT GREEN (-5775 5225);
DISPLAY INVISIBLE (-5775 5225);
FORCEPROP 1 LAST COMMENT_BODY TRUE
J 0
(-6000 5275);
DISPLAY 0.872340 (-6000 5275);
PAINT GREEN (-6000 5275);
DISPLAY INVISIBLE (-6000 5275);
FORCEPROP 2 LAST PATH I67
J 0
(-6300 5400);
DISPLAY 0.680851 (-6300 5400);
DISPLAY INVISIBLE (-6300 5400);
FORCEADD OFFPAGE..5
(-6125 5900);
FORCEPROP 2 LAST $XR1 54 
J 0
(-6439 5900);
DISPLAY 0.638298 (-6439 5900);
PAINT MONO (-6439 5900);
FORCEPROP 2 LAST $XR0 81 
J 0
(-6349 5900);
DISPLAY 0.638298 (-6349 5900);
PAINT MONO (-6349 5900);
FORCEPROP 2 LAST CDS_LIB standard
J 0
(-6125 5900);
DISPLAY INVISIBLE (-6125 5900);
FORCEPROP 1 LAST OFFPAGE TRUE
J 0
(-5800 5775);
DISPLAY 0.872340 (-5800 5775);
PAINT GREEN (-5800 5775);
DISPLAY INVISIBLE (-5800 5775);
FORCEPROP 1 LAST COMMENT_BODY TRUE
J 0
(-6025 5825);
DISPLAY 0.872340 (-6025 5825);
PAINT GREEN (-6025 5825);
DISPLAY INVISIBLE (-6025 5825);
FORCEPROP 2 LAST PATH I68
J 0
(-6325 5950);
DISPLAY 0.680851 (-6325 5950);
DISPLAY INVISIBLE (-6325 5950);
FORCEADD OFFPAGE..5
(-6125 5850);
FORCEPROP 2 LAST $XR1 54 
J 0
(-6439 5850);
DISPLAY 0.638298 (-6439 5850);
PAINT MONO (-6439 5850);
FORCEPROP 2 LAST $XR0 81 
J 0
(-6349 5850);
DISPLAY 0.638298 (-6349 5850);
PAINT MONO (-6349 5850);
FORCEPROP 2 LAST CDS_LIB standard
J 0
(-6125 5850);
DISPLAY INVISIBLE (-6125 5850);
FORCEPROP 1 LAST OFFPAGE TRUE
J 0
(-5800 5725);
DISPLAY 0.872340 (-5800 5725);
PAINT GREEN (-5800 5725);
DISPLAY INVISIBLE (-5800 5725);
FORCEPROP 1 LAST COMMENT_BODY TRUE
J 0
(-6025 5775);
DISPLAY 0.872340 (-6025 5775);
PAINT GREEN (-6025 5775);
DISPLAY INVISIBLE (-6025 5775);
FORCEPROP 2 LAST PATH I69
J 0
(-6325 5900);
DISPLAY 0.680851 (-6325 5900);
DISPLAY INVISIBLE (-6325 5900);
FORCEADD OFFPAGE..5
(-8225 3600);
FORCEPROP 2 LAST $XR3 136 
J 0
(-8809 3600);
DISPLAY 0.638298 (-8809 3600);
PAINT MONO (-8809 3600);
FORCEPROP 2 LAST $XR2 135 
J 0
(-8689 3600);
DISPLAY 0.638298 (-8689 3600);
PAINT MONO (-8689 3600);
FORCEPROP 2 LAST $XR1 134 
J 0
(-8569 3600);
DISPLAY 0.638298 (-8569 3600);
PAINT MONO (-8569 3600);
FORCEPROP 2 LAST $XR0 80 
J 0
(-8449 3600);
DISPLAY 0.638298 (-8449 3600);
PAINT MONO (-8449 3600);
FORCEPROP 2 LAST CDS_LIB standard
J 0
(-8225 3600);
DISPLAY INVISIBLE (-8225 3600);
FORCEPROP 1 LAST OFFPAGE TRUE
J 0
(-7900 3475);
DISPLAY 0.872340 (-7900 3475);
PAINT GREEN (-7900 3475);
DISPLAY INVISIBLE (-7900 3475);
FORCEPROP 1 LAST COMMENT_BODY TRUE
J 0
(-8125 3525);
DISPLAY 0.872340 (-8125 3525);
PAINT GREEN (-8125 3525);
DISPLAY INVISIBLE (-8125 3525);
FORCEPROP 2 LAST PATH I7
J 0
(-8475 3650);
DISPLAY 0.680851 (-8475 3650);
DISPLAY INVISIBLE (-8475 3650);
FORCEADD VCC_CORE..1
(-6825 6375);
FORCEPROP 3 LASTPIN (-6825 6325) SIG_NAME P1V8_AUX\g
J 0
(-6815 6335);
DISPLAY 0.659574 (-6815 6335);
PAINT MONO (-6815 6335);
DISPLAY INVISIBLE (-6815 6335);
FORCEPROP 1 LAST HDL_POWER P1V8_AUX
J 1
(-6825 6425);
DISPLAY 0.489362 (-6825 6425);
PAINT GREEN (-6825 6425);
FORCEPROP 2 LAST CDS_LIB pure_quanta_power
J 0
(-6825 6375);
DISPLAY INVISIBLE (-6825 6375);
FORCEPROP 1 LAST PATH I70
J 0
(-6775 6400);
DISPLAY 0.872340 (-6775 6400);
PAINT AQUA (-6775 6400);
DISPLAY INVISIBLE (-6775 6400);
FORCEADD Q_RES..1
(-4925 5275);
FORCEPROP 1 LAST LOCATION R1351
J 0
(-5275 5275);
DISPLAY 0.489362 (-5275 5275);
PAINT SKYBLUE (-5275 5275);
FORCEPROP 0 LAST $SEC 1
J 0
(-4675 5325);
DISPLAY 0.680851 (-4675 5325);
PAINT MONO (-4675 5325);
DISPLAY INVISIBLE (-4675 5325);
FORCEPROP 0 LAST CDS_SEC 1
J 0
(-4725 5350);
DISPLAY 0.680851 (-4725 5350);
DISPLAY INVISIBLE (-4725 5350);
FORCEPROP 1 LASTPIN (-5025 5275) $PN 1
J 0
(-5013 5287);
DISPLAY 0.489362 (-5013 5287);
PAINT MONO (-5013 5287);
FORCEPROP 1 LASTPIN (-4825 5275) $PN 2
J 0
(-4863 5287);
DISPLAY 0.489362 (-4863 5287);
PAINT MONO (-4863 5287);
FORCEPROP 1 LAST VALUE 2.2K
J 2
(-4675 5275);
DISPLAY 0.489362 (-4675 5275);
PAINT SKYBLUE (-4675 5275);
FORCEPROP 1 LAST PACK_TYPE 0402LF
J 0
(-4675 5125);
DISPLAY 0.978723 (-4675 5125);
PAINT SKYBLUE (-4675 5125);
DISPLAY INVISIBLE (-4675 5125);
FORCEPROP 1 LAST TOLERANCE 5%
J 0
(-4925 5175);
DISPLAY 0.978723 (-4925 5175);
PAINT SKYBLUE (-4925 5175);
DISPLAY INVISIBLE (-4925 5175);
FORCEPROP 1 LAST MATERIAL CHIP
J 0
(-4925 5125);
DISPLAY 0.978723 (-4925 5125);
PAINT SKYBLUE (-4925 5125);
DISPLAY INVISIBLE (-4925 5125);
FORCEPROP 1 LAST WATTAGE 1/16W
J 2
(-4950 5125);
DISPLAY 0.978723 (-4950 5125);
PAINT SKYBLUE (-4950 5125);
DISPLAY INVISIBLE (-4950 5125);
FORCEPROP 2 LAST CDS_LIB pure_quanta
J 0
(-4925 5275);
DISPLAY INVISIBLE (-4925 5275);
FORCEPROP 1 LAST PATH I72
J 0
(-4975 5425);
DISPLAY 0.978723 (-4975 5425);
PAINT WHITE (-4975 5425);
DISPLAY INVISIBLE (-4975 5425);
FORCEPROP 1 LAST PART_NUMBER CS22202JB07
J 0
(-4975 5375);
DISPLAY 0.978723 (-4975 5375);
PAINT SKYBLUE (-4975 5375);
DISPLAY INVISIBLE (-4975 5375);
FORCEADD Q_RES..1
(-4925 5350);
FORCEPROP 1 LAST LOCATION R1288
J 0
(-5275 5350);
DISPLAY 0.489362 (-5275 5350);
PAINT SKYBLUE (-5275 5350);
FORCEPROP 0 LAST $SEC 1
J 0
(-5050 5400);
DISPLAY 0.680851 (-5050 5400);
PAINT MONO (-5050 5400);
DISPLAY INVISIBLE (-5050 5400);
FORCEPROP 0 LAST CDS_SEC 1
J 0
(-5050 5400);
DISPLAY 0.680851 (-5050 5400);
DISPLAY INVISIBLE (-5050 5400);
FORCEPROP 1 LASTPIN (-5025 5350) $PN 1
J 0
(-5013 5362);
DISPLAY 0.489362 (-5013 5362);
PAINT MONO (-5013 5362);
FORCEPROP 1 LASTPIN (-4825 5350) $PN 2
J 0
(-4863 5362);
DISPLAY 0.489362 (-4863 5362);
PAINT MONO (-4863 5362);
FORCEPROP 1 LAST VALUE 4.7K
J 0
(-4800 5350);
DISPLAY 0.489362 (-4800 5350);
PAINT SKYBLUE (-4800 5350);
FORCEPROP 2 LAST CDS_LIB pure_quanta
J 0
(-4925 5350);
DISPLAY INVISIBLE (-4925 5350);
FORCEPROP 1 LAST WATTAGE 1/16W
J 2
(-4950 5200);
DISPLAY 0.510638 (-4950 5200);
PAINT SKYBLUE (-4950 5200);
DISPLAY INVISIBLE (-4950 5200);
FORCEPROP 1 LAST MATERIAL CHIP
J 0
(-4825 5325);
DISPLAY 0.489362 (-4825 5325);
PAINT SKYBLUE (-4825 5325);
DISPLAY INVISIBLE (-4825 5325);
FORCEPROP 1 LAST TOLERANCE 5%
J 0
(-4800 5350);
DISPLAY 0.510638 (-4800 5350);
PAINT SKYBLUE (-4800 5350);
DISPLAY INVISIBLE (-4800 5350);
FORCEPROP 1 LAST PACK_TYPE 0402LF
J 0
(-4675 5200);
DISPLAY 0.510638 (-4675 5200);
PAINT SKYBLUE (-4675 5200);
DISPLAY INVISIBLE (-4675 5200);
FORCEPROP 1 LAST PATH I73
J 0
(-4975 5500);
DISPLAY 0.978723 (-4975 5500);
PAINT WHITE (-4975 5500);
DISPLAY INVISIBLE (-4975 5500);
FORCEPROP 1 LAST PART_NUMBER CS24702JB10
J 0
(-4975 5450);
DISPLAY 0.510638 (-4975 5450);
PAINT SKYBLUE (-4975 5450);
DISPLAY INVISIBLE (-4975 5450);
FORCEADD Q_RES..1
(-4925 5400);
FORCEPROP 1 LAST LOCATION R1287
J 0
(-5275 5400);
DISPLAY 0.489362 (-5275 5400);
PAINT SKYBLUE (-5275 5400);
FORCEPROP 0 LAST $SEC 1
J 0
(-5050 5450);
DISPLAY 0.680851 (-5050 5450);
PAINT MONO (-5050 5450);
DISPLAY INVISIBLE (-5050 5450);
FORCEPROP 0 LAST CDS_SEC 1
J 0
(-5050 5450);
DISPLAY 0.680851 (-5050 5450);
DISPLAY INVISIBLE (-5050 5450);
FORCEPROP 1 LASTPIN (-5025 5400) $PN 1
J 0
(-5013 5412);
DISPLAY 0.489362 (-5013 5412);
PAINT MONO (-5013 5412);
FORCEPROP 1 LASTPIN (-4825 5400) $PN 2
J 0
(-4863 5412);
DISPLAY 0.489362 (-4863 5412);
PAINT MONO (-4863 5412);
FORCEPROP 1 LAST VALUE 4.7K
J 0
(-4800 5400);
DISPLAY 0.489362 (-4800 5400);
PAINT SKYBLUE (-4800 5400);
FORCEPROP 2 LAST CDS_LIB pure_quanta
J 0
(-4925 5400);
DISPLAY INVISIBLE (-4925 5400);
FORCEPROP 1 LAST WATTAGE 1/16W
J 2
(-4950 5250);
DISPLAY 0.510638 (-4950 5250);
PAINT SKYBLUE (-4950 5250);
DISPLAY INVISIBLE (-4950 5250);
FORCEPROP 1 LAST MATERIAL CHIP
J 0
(-4825 5375);
DISPLAY 0.489362 (-4825 5375);
PAINT SKYBLUE (-4825 5375);
DISPLAY INVISIBLE (-4825 5375);
FORCEPROP 1 LAST TOLERANCE 5%
J 0
(-4800 5400);
DISPLAY 0.510638 (-4800 5400);
PAINT SKYBLUE (-4800 5400);
DISPLAY INVISIBLE (-4800 5400);
FORCEPROP 1 LAST PACK_TYPE 0402LF
J 0
(-4675 5250);
DISPLAY 0.510638 (-4675 5250);
PAINT SKYBLUE (-4675 5250);
DISPLAY INVISIBLE (-4675 5250);
FORCEPROP 1 LAST PATH I74
J 0
(-4975 5550);
DISPLAY 0.978723 (-4975 5550);
PAINT WHITE (-4975 5550);
DISPLAY INVISIBLE (-4975 5550);
FORCEPROP 1 LAST PART_NUMBER CS24702JB10
J 0
(-4975 5500);
DISPLAY 0.510638 (-4975 5500);
PAINT SKYBLUE (-4975 5500);
DISPLAY INVISIBLE (-4975 5500);
FORCEADD VCC_CORE..1
(-4650 5550);
FORCEPROP 3 LASTPIN (-4650 5500) SIG_NAME PVDD18_S5_P0\g
J 0
(-4640 5510);
DISPLAY 0.659574 (-4640 5510);
PAINT MONO (-4640 5510);
DISPLAY INVISIBLE (-4640 5510);
FORCEPROP 1 LAST HDL_POWER PVDD18_S5_P0
J 1
(-4650 5600);
DISPLAY 0.489362 (-4650 5600);
PAINT GREEN (-4650 5600);
FORCEPROP 2 LAST CDS_LIB pure_quanta_power
J 0
(-4650 5550);
DISPLAY INVISIBLE (-4650 5550);
FORCEPROP 1 LAST PATH I75
J 0
(-4600 5575);
DISPLAY 0.872340 (-4600 5575);
PAINT AQUA (-4600 5575);
DISPLAY INVISIBLE (-4600 5575);
FORCEADD Q_RES..1
(-4925 5850);
FORCEPROP 1 LAST LOCATION R1286
J 0
(-5275 5850);
DISPLAY 0.489362 (-5275 5850);
PAINT SKYBLUE (-5275 5850);
FORCEPROP 0 LAST $SEC 1
J 0
(-5050 5900);
DISPLAY 0.680851 (-5050 5900);
PAINT MONO (-5050 5900);
DISPLAY INVISIBLE (-5050 5900);
FORCEPROP 0 LAST CDS_SEC 1
J 0
(-5050 5900);
DISPLAY 0.680851 (-5050 5900);
DISPLAY INVISIBLE (-5050 5900);
FORCEPROP 1 LASTPIN (-5025 5850) $PN 1
J 0
(-5013 5862);
DISPLAY 0.489362 (-5013 5862);
PAINT MONO (-5013 5862);
FORCEPROP 1 LASTPIN (-4825 5850) $PN 2
J 0
(-4863 5862);
DISPLAY 0.489362 (-4863 5862);
PAINT MONO (-4863 5862);
FORCEPROP 1 LAST VALUE 4.7K
J 0
(-4800 5850);
DISPLAY 0.489362 (-4800 5850);
PAINT SKYBLUE (-4800 5850);
FORCEPROP 2 LAST CDS_LIB pure_quanta
J 0
(-4925 5850);
DISPLAY INVISIBLE (-4925 5850);
FORCEPROP 1 LAST WATTAGE 1/16W
J 2
(-4950 5700);
DISPLAY 0.510638 (-4950 5700);
PAINT SKYBLUE (-4950 5700);
DISPLAY INVISIBLE (-4950 5700);
FORCEPROP 1 LAST MATERIAL CHIP
J 0
(-4825 5825);
DISPLAY 0.489362 (-4825 5825);
PAINT SKYBLUE (-4825 5825);
DISPLAY INVISIBLE (-4825 5825);
FORCEPROP 1 LAST TOLERANCE 5%
J 0
(-4800 5850);
DISPLAY 0.510638 (-4800 5850);
PAINT SKYBLUE (-4800 5850);
DISPLAY INVISIBLE (-4800 5850);
FORCEPROP 1 LAST PACK_TYPE 0402LF
J 0
(-4675 5700);
DISPLAY 0.510638 (-4675 5700);
PAINT SKYBLUE (-4675 5700);
DISPLAY INVISIBLE (-4675 5700);
FORCEPROP 1 LAST PATH I76
J 0
(-4975 6000);
DISPLAY 0.978723 (-4975 6000);
PAINT WHITE (-4975 6000);
DISPLAY INVISIBLE (-4975 6000);
FORCEPROP 1 LAST PART_NUMBER CS24702JB10
J 0
(-4975 5950);
DISPLAY 0.510638 (-4975 5950);
PAINT SKYBLUE (-4975 5950);
DISPLAY INVISIBLE (-4975 5950);
FORCEADD Q_RES..1
(-4925 5900);
FORCEPROP 1 LAST LOCATION R1285
J 0
(-5275 5900);
DISPLAY 0.489362 (-5275 5900);
PAINT SKYBLUE (-5275 5900);
FORCEPROP 0 LAST $SEC 1
J 0
(-5050 5950);
DISPLAY 0.680851 (-5050 5950);
PAINT MONO (-5050 5950);
DISPLAY INVISIBLE (-5050 5950);
FORCEPROP 0 LAST CDS_SEC 1
J 0
(-5050 5950);
DISPLAY 0.680851 (-5050 5950);
DISPLAY INVISIBLE (-5050 5950);
FORCEPROP 1 LASTPIN (-5025 5900) $PN 1
J 0
(-5013 5912);
DISPLAY 0.489362 (-5013 5912);
PAINT MONO (-5013 5912);
FORCEPROP 1 LASTPIN (-4825 5900) $PN 2
J 0
(-4863 5912);
DISPLAY 0.489362 (-4863 5912);
PAINT MONO (-4863 5912);
FORCEPROP 1 LAST VALUE 4.7K
J 0
(-4800 5900);
DISPLAY 0.489362 (-4800 5900);
PAINT SKYBLUE (-4800 5900);
FORCEPROP 2 LAST CDS_LIB pure_quanta
J 0
(-4925 5900);
DISPLAY INVISIBLE (-4925 5900);
FORCEPROP 1 LAST WATTAGE 1/16W
J 2
(-4950 5750);
DISPLAY 0.510638 (-4950 5750);
PAINT SKYBLUE (-4950 5750);
DISPLAY INVISIBLE (-4950 5750);
FORCEPROP 1 LAST MATERIAL CHIP
J 0
(-4825 5875);
DISPLAY 0.489362 (-4825 5875);
PAINT SKYBLUE (-4825 5875);
DISPLAY INVISIBLE (-4825 5875);
FORCEPROP 1 LAST TOLERANCE 5%
J 0
(-4800 5900);
DISPLAY 0.510638 (-4800 5900);
PAINT SKYBLUE (-4800 5900);
DISPLAY INVISIBLE (-4800 5900);
FORCEPROP 1 LAST PACK_TYPE 0402LF
J 0
(-4675 5750);
DISPLAY 0.510638 (-4675 5750);
PAINT SKYBLUE (-4675 5750);
DISPLAY INVISIBLE (-4675 5750);
FORCEPROP 1 LAST PATH I77
J 0
(-4975 6050);
DISPLAY 0.978723 (-4975 6050);
PAINT WHITE (-4975 6050);
DISPLAY INVISIBLE (-4975 6050);
FORCEPROP 1 LAST PART_NUMBER CS24702JB10
J 0
(-4975 6000);
DISPLAY 0.510638 (-4975 6000);
PAINT SKYBLUE (-4975 6000);
DISPLAY INVISIBLE (-4975 6000);
FORCEADD VCC_CORE..1
(-4650 6025);
FORCEPROP 3 LASTPIN (-4650 5975) SIG_NAME PVDD18_S5_P1\g
J 0
(-4640 5985);
DISPLAY 0.659574 (-4640 5985);
PAINT MONO (-4640 5985);
DISPLAY INVISIBLE (-4640 5985);
FORCEPROP 1 LAST HDL_POWER PVDD18_S5_P1
J 1
(-4650 6075);
DISPLAY 0.489362 (-4650 6075);
PAINT GREEN (-4650 6075);
FORCEPROP 2 LAST CDS_LIB pure_quanta_power
J 0
(-4650 6025);
DISPLAY INVISIBLE (-4650 6025);
FORCEPROP 1 LAST PATH I78
J 0
(-4600 6050);
DISPLAY 0.872340 (-4600 6050);
PAINT AQUA (-4600 6050);
DISPLAY INVISIBLE (-4600 6050);
FORCEADD Q_CAP..2
(-3450 1075);
FORCEPROP 1 LAST LOCATION C1134
J 0
(-3750 1075);
DISPLAY 0.489362 (-3750 1075);
PAINT SKYBLUE (-3750 1075);
FORCEPROP 0 LAST $SEC 1
J 0
(-3075 1125);
DISPLAY 0.680851 (-3075 1125);
PAINT MONO (-3075 1125);
DISPLAY INVISIBLE (-3075 1125);
FORCEPROP 0 LAST CDS_SEC 1
J 0
(-3075 1125);
DISPLAY 1.021277 (-3075 1125);
DISPLAY INVISIBLE (-3075 1125);
FORCEPROP 1 LASTPIN (-3550 1075) $PN 1
J 0
(-3560 1090);
DISPLAY 0.489362 (-3560 1090);
PAINT MONO (-3560 1090);
FORCEPROP 1 LASTPIN (-3350 1075) $PN 2
J 0
(-3365 1090);
DISPLAY 0.489362 (-3365 1090);
PAINT MONO (-3365 1090);
FORCEPROP 1 LAST VALUE 0.1UF
J 2
(-3075 1075);
DISPLAY 0.489362 (-3075 1075);
PAINT SKYBLUE (-3075 1075);
FORCEPROP 1 LAST PACK_TYPE C0402
J 1
(-2600 1025);
DISPLAY 0.978723 (-2600 1025);
PAINT SKYBLUE (-2600 1025);
DISPLAY INVISIBLE (-2600 1025);
FORCEPROP 1 LAST VOLTAGE 16V
J 0
(-2925 1025);
DISPLAY 0.978723 (-2925 1025);
PAINT SKYBLUE (-2925 1025);
DISPLAY INVISIBLE (-2925 1025);
FORCEPROP 1 LAST TOLERANCE 10%
J 2
(-3175 1025);
DISPLAY 0.978723 (-3175 1025);
PAINT SKYBLUE (-3175 1025);
DISPLAY INVISIBLE (-3175 1025);
FORCEPROP 1 LAST MATERIAL X7R
J 0
(-3100 1025);
DISPLAY 0.978723 (-3100 1025);
PAINT SKYBLUE (-3100 1025);
DISPLAY INVISIBLE (-3100 1025);
FORCEPROP 2 LAST CDS_LIB pure_quanta
J 0
(-3450 1075);
DISPLAY INVISIBLE (-3450 1075);
FORCEPROP 1 LAST PATH I79
J 0
(-3450 1275);
DISPLAY 0.978723 (-3450 1275);
PAINT WHITE (-3450 1275);
DISPLAY INVISIBLE (-3450 1275);
FORCEPROP 1 LAST PART_NUMBER CH4103K1B08
J 1
(-2700 1075);
DISPLAY 0.978723 (-2700 1075);
PAINT SKYBLUE (-2700 1075);
DISPLAY INVISIBLE (-2700 1075);
FORCEADD OFFPAGE..5
(-8225 3650);
FORCEPROP 2 LAST $XR3 248 
J 0
(-8809 3650);
DISPLAY 0.638298 (-8809 3650);
PAINT MONO (-8809 3650);
FORCEPROP 2 LAST $XR2 135 
J 0
(-8689 3650);
DISPLAY 0.638298 (-8689 3650);
PAINT MONO (-8689 3650);
FORCEPROP 2 LAST $XR1 134 
J 0
(-8569 3650);
DISPLAY 0.638298 (-8569 3650);
PAINT MONO (-8569 3650);
FORCEPROP 2 LAST $XR0 80 
J 0
(-8449 3650);
DISPLAY 0.638298 (-8449 3650);
PAINT MONO (-8449 3650);
FORCEPROP 2 LAST CDS_LIB standard
J 0
(-8225 3650);
DISPLAY INVISIBLE (-8225 3650);
FORCEPROP 1 LAST OFFPAGE TRUE
J 0
(-7900 3525);
DISPLAY 0.872340 (-7900 3525);
PAINT GREEN (-7900 3525);
DISPLAY INVISIBLE (-7900 3525);
FORCEPROP 1 LAST COMMENT_BODY TRUE
J 0
(-8125 3575);
DISPLAY 0.872340 (-8125 3575);
PAINT GREEN (-8125 3575);
DISPLAY INVISIBLE (-8125 3575);
FORCEPROP 2 LAST PATH I8
J 0
(-8475 3700);
DISPLAY 0.680851 (-8475 3700);
DISPLAY INVISIBLE (-8475 3700);
FORCEADD Q_CAP..2
(-3450 1275);
FORCEPROP 1 LAST LOCATION C1132
J 0
(-3750 1275);
DISPLAY 0.489362 (-3750 1275);
PAINT SKYBLUE (-3750 1275);
FORCEPROP 0 LAST $SEC 1
J 0
(-3075 1325);
DISPLAY 0.680851 (-3075 1325);
PAINT MONO (-3075 1325);
DISPLAY INVISIBLE (-3075 1325);
FORCEPROP 0 LAST CDS_SEC 1
J 0
(-3075 1325);
DISPLAY 1.021277 (-3075 1325);
DISPLAY INVISIBLE (-3075 1325);
FORCEPROP 1 LASTPIN (-3550 1275) $PN 1
J 0
(-3560 1290);
DISPLAY 0.489362 (-3560 1290);
PAINT MONO (-3560 1290);
FORCEPROP 1 LASTPIN (-3350 1275) $PN 2
J 0
(-3365 1290);
DISPLAY 0.489362 (-3365 1290);
PAINT MONO (-3365 1290);
FORCEPROP 1 LAST VALUE 0.1UF
J 2
(-3075 1275);
DISPLAY 0.489362 (-3075 1275);
PAINT SKYBLUE (-3075 1275);
FORCEPROP 1 LAST PACK_TYPE C0402
J 1
(-2600 1225);
DISPLAY 0.978723 (-2600 1225);
PAINT SKYBLUE (-2600 1225);
DISPLAY INVISIBLE (-2600 1225);
FORCEPROP 1 LAST VOLTAGE 16V
J 0
(-2925 1225);
DISPLAY 0.978723 (-2925 1225);
PAINT SKYBLUE (-2925 1225);
DISPLAY INVISIBLE (-2925 1225);
FORCEPROP 1 LAST TOLERANCE 10%
J 2
(-3175 1225);
DISPLAY 0.978723 (-3175 1225);
PAINT SKYBLUE (-3175 1225);
DISPLAY INVISIBLE (-3175 1225);
FORCEPROP 1 LAST MATERIAL X7R
J 0
(-3100 1225);
DISPLAY 0.978723 (-3100 1225);
PAINT SKYBLUE (-3100 1225);
DISPLAY INVISIBLE (-3100 1225);
FORCEPROP 2 LAST CDS_LIB pure_quanta
J 0
(-3450 1275);
DISPLAY INVISIBLE (-3450 1275);
FORCEPROP 1 LAST PATH I80
J 0
(-3450 1475);
DISPLAY 0.978723 (-3450 1475);
PAINT WHITE (-3450 1475);
DISPLAY INVISIBLE (-3450 1475);
FORCEPROP 1 LAST PART_NUMBER CH4103K1B08
J 1
(-2700 1275);
DISPLAY 0.978723 (-2700 1275);
PAINT SKYBLUE (-2700 1275);
DISPLAY INVISIBLE (-2700 1275);
FORCEADD Q_CAP..2
(-3450 1175);
FORCEPROP 1 LAST LOCATION C1133
J 0
(-3750 1175);
DISPLAY 0.489362 (-3750 1175);
PAINT SKYBLUE (-3750 1175);
FORCEPROP 0 LAST $SEC 1
J 0
(-3075 1225);
DISPLAY 0.680851 (-3075 1225);
PAINT MONO (-3075 1225);
DISPLAY INVISIBLE (-3075 1225);
FORCEPROP 0 LAST CDS_SEC 1
J 0
(-3075 1225);
DISPLAY 1.021277 (-3075 1225);
DISPLAY INVISIBLE (-3075 1225);
FORCEPROP 1 LASTPIN (-3550 1175) $PN 1
J 0
(-3560 1190);
DISPLAY 0.489362 (-3560 1190);
PAINT MONO (-3560 1190);
FORCEPROP 1 LASTPIN (-3350 1175) $PN 2
J 0
(-3365 1190);
DISPLAY 0.489362 (-3365 1190);
PAINT MONO (-3365 1190);
FORCEPROP 1 LAST VALUE 0.1UF
J 2
(-3075 1175);
DISPLAY 0.489362 (-3075 1175);
PAINT SKYBLUE (-3075 1175);
FORCEPROP 1 LAST PACK_TYPE C0402
J 1
(-2600 1125);
DISPLAY 0.978723 (-2600 1125);
PAINT SKYBLUE (-2600 1125);
DISPLAY INVISIBLE (-2600 1125);
FORCEPROP 1 LAST VOLTAGE 16V
J 0
(-2925 1125);
DISPLAY 0.978723 (-2925 1125);
PAINT SKYBLUE (-2925 1125);
DISPLAY INVISIBLE (-2925 1125);
FORCEPROP 1 LAST TOLERANCE 10%
J 2
(-3175 1125);
DISPLAY 0.978723 (-3175 1125);
PAINT SKYBLUE (-3175 1125);
DISPLAY INVISIBLE (-3175 1125);
FORCEPROP 1 LAST MATERIAL X7R
J 0
(-3100 1125);
DISPLAY 0.978723 (-3100 1125);
PAINT SKYBLUE (-3100 1125);
DISPLAY INVISIBLE (-3100 1125);
FORCEPROP 2 LAST CDS_LIB pure_quanta
J 0
(-3450 1175);
DISPLAY INVISIBLE (-3450 1175);
FORCEPROP 1 LAST PATH I81
J 0
(-3450 1375);
DISPLAY 0.978723 (-3450 1375);
PAINT WHITE (-3450 1375);
DISPLAY INVISIBLE (-3450 1375);
FORCEPROP 1 LAST PART_NUMBER CH4103K1B08
J 1
(-2700 1175);
DISPLAY 0.978723 (-2700 1175);
PAINT SKYBLUE (-2700 1175);
DISPLAY INVISIBLE (-2700 1175);
FORCEADD Q_CAP..2
(-3450 1375);
FORCEPROP 1 LAST LOCATION C1131
J 0
(-3750 1375);
DISPLAY 0.489362 (-3750 1375);
PAINT SKYBLUE (-3750 1375);
FORCEPROP 0 LAST $SEC 1
J 0
(-3075 1425);
DISPLAY 0.680851 (-3075 1425);
PAINT MONO (-3075 1425);
DISPLAY INVISIBLE (-3075 1425);
FORCEPROP 0 LAST CDS_SEC 1
J 0
(-3075 1425);
DISPLAY 1.021277 (-3075 1425);
DISPLAY INVISIBLE (-3075 1425);
FORCEPROP 1 LASTPIN (-3550 1375) $PN 1
J 0
(-3560 1390);
DISPLAY 0.489362 (-3560 1390);
PAINT MONO (-3560 1390);
FORCEPROP 1 LASTPIN (-3350 1375) $PN 2
J 0
(-3365 1390);
DISPLAY 0.489362 (-3365 1390);
PAINT MONO (-3365 1390);
FORCEPROP 1 LAST VALUE 0.1UF
J 2
(-3075 1375);
DISPLAY 0.489362 (-3075 1375);
PAINT SKYBLUE (-3075 1375);
FORCEPROP 1 LAST PACK_TYPE C0402
J 1
(-2600 1325);
DISPLAY 0.978723 (-2600 1325);
PAINT SKYBLUE (-2600 1325);
DISPLAY INVISIBLE (-2600 1325);
FORCEPROP 1 LAST VOLTAGE 16V
J 0
(-2925 1325);
DISPLAY 0.978723 (-2925 1325);
PAINT SKYBLUE (-2925 1325);
DISPLAY INVISIBLE (-2925 1325);
FORCEPROP 1 LAST TOLERANCE 10%
J 2
(-3175 1325);
DISPLAY 0.978723 (-3175 1325);
PAINT SKYBLUE (-3175 1325);
DISPLAY INVISIBLE (-3175 1325);
FORCEPROP 1 LAST MATERIAL X7R
J 0
(-3100 1325);
DISPLAY 0.978723 (-3100 1325);
PAINT SKYBLUE (-3100 1325);
DISPLAY INVISIBLE (-3100 1325);
FORCEPROP 2 LAST CDS_LIB pure_quanta
J 0
(-3450 1375);
DISPLAY INVISIBLE (-3450 1375);
FORCEPROP 1 LAST PATH I82
J 0
(-3450 1575);
DISPLAY 0.978723 (-3450 1575);
PAINT WHITE (-3450 1575);
DISPLAY INVISIBLE (-3450 1575);
FORCEPROP 1 LAST PART_NUMBER CH4103K1B08
J 1
(-2700 1375);
DISPLAY 0.978723 (-2700 1375);
PAINT SKYBLUE (-2700 1375);
DISPLAY INVISIBLE (-2700 1375);
FORCEADD Q_CAP..2
(-3450 1575);
FORCEPROP 1 LAST LOCATION C352
J 0
(-3750 1575);
DISPLAY 0.489362 (-3750 1575);
PAINT SKYBLUE (-3750 1575);
FORCEPROP 2 LAST $SEC 1
J 0
(-3450 1825);
DISPLAY 0.680851 (-3450 1825);
PAINT MONO (-3450 1825);
DISPLAY INVISIBLE (-3450 1825);
FORCEPROP 2 LAST CDS_SEC 1
J 0
(-3450 1825);
DISPLAY 1.021277 (-3450 1825);
DISPLAY INVISIBLE (-3450 1825);
FORCEPROP 1 LASTPIN (-3550 1575) $PN 1
J 0
(-3560 1590);
DISPLAY 0.489362 (-3560 1590);
PAINT MONO (-3560 1590);
FORCEPROP 1 LASTPIN (-3350 1575) $PN 2
J 0
(-3365 1590);
DISPLAY 0.489362 (-3365 1590);
PAINT MONO (-3365 1590);
FORCEPROP 1 LAST VALUE 0.1UF
J 2
(-3075 1575);
DISPLAY 0.489362 (-3075 1575);
PAINT SKYBLUE (-3075 1575);
FORCEPROP 1 LAST PACK_TYPE C0402
J 1
(-2600 1525);
DISPLAY 0.489362 (-2600 1525);
PAINT SKYBLUE (-2600 1525);
DISPLAY INVISIBLE (-2600 1525);
FORCEPROP 1 LAST VOLTAGE 16V
J 0
(-2925 1525);
DISPLAY 0.489362 (-2925 1525);
PAINT SKYBLUE (-2925 1525);
DISPLAY INVISIBLE (-2925 1525);
FORCEPROP 1 LAST TOLERANCE 10%
J 2
(-3175 1525);
DISPLAY 0.489362 (-3175 1525);
PAINT SKYBLUE (-3175 1525);
DISPLAY INVISIBLE (-3175 1525);
FORCEPROP 1 LAST MATERIAL X7R
J 0
(-3100 1525);
DISPLAY 0.489362 (-3100 1525);
PAINT SKYBLUE (-3100 1525);
DISPLAY INVISIBLE (-3100 1525);
FORCEPROP 2 LAST CDS_LIB pure_quanta
J 0
(-3450 1575);
DISPLAY INVISIBLE (-3450 1575);
FORCEPROP 1 LAST PATH I83
J 0
(-3450 1775);
DISPLAY 0.978723 (-3450 1775);
PAINT WHITE (-3450 1775);
DISPLAY INVISIBLE (-3450 1775);
FORCEPROP 1 LAST PART_NUMBER CH4103K1B08
J 1
(-2700 1575);
DISPLAY 0.489362 (-2700 1575);
PAINT SKYBLUE (-2700 1575);
DISPLAY INVISIBLE (-2700 1575);
FORCEADD Q_CAP..2
(-3450 1775);
FORCEPROP 1 LAST LOCATION C1128
J 0
(-3750 1775);
DISPLAY 0.489362 (-3750 1775);
PAINT SKYBLUE (-3750 1775);
FORCEPROP 0 LAST $SEC 1
J 0
(-3075 1825);
DISPLAY 0.680851 (-3075 1825);
PAINT MONO (-3075 1825);
DISPLAY INVISIBLE (-3075 1825);
FORCEPROP 0 LAST CDS_SEC 1
J 0
(-3075 1825);
DISPLAY 1.021277 (-3075 1825);
DISPLAY INVISIBLE (-3075 1825);
FORCEPROP 1 LASTPIN (-3550 1775) $PN 1
J 0
(-3560 1790);
DISPLAY 0.489362 (-3560 1790);
PAINT MONO (-3560 1790);
FORCEPROP 1 LASTPIN (-3350 1775) $PN 2
J 0
(-3365 1790);
DISPLAY 0.489362 (-3365 1790);
PAINT MONO (-3365 1790);
FORCEPROP 1 LAST VALUE 0.1UF
J 2
(-3075 1775);
DISPLAY 0.489362 (-3075 1775);
PAINT SKYBLUE (-3075 1775);
FORCEPROP 1 LAST PACK_TYPE C0402
J 1
(-2600 1725);
DISPLAY 0.978723 (-2600 1725);
PAINT SKYBLUE (-2600 1725);
DISPLAY INVISIBLE (-2600 1725);
FORCEPROP 1 LAST VOLTAGE 16V
J 0
(-2925 1725);
DISPLAY 0.978723 (-2925 1725);
PAINT SKYBLUE (-2925 1725);
DISPLAY INVISIBLE (-2925 1725);
FORCEPROP 1 LAST TOLERANCE 10%
J 2
(-3175 1725);
DISPLAY 0.978723 (-3175 1725);
PAINT SKYBLUE (-3175 1725);
DISPLAY INVISIBLE (-3175 1725);
FORCEPROP 1 LAST MATERIAL X7R
J 0
(-3100 1725);
DISPLAY 0.978723 (-3100 1725);
PAINT SKYBLUE (-3100 1725);
DISPLAY INVISIBLE (-3100 1725);
FORCEPROP 2 LAST CDS_LIB pure_quanta
J 0
(-3450 1775);
DISPLAY INVISIBLE (-3450 1775);
FORCEPROP 1 LAST PATH I84
J 0
(-3450 1975);
DISPLAY 0.978723 (-3450 1975);
PAINT WHITE (-3450 1975);
DISPLAY INVISIBLE (-3450 1975);
FORCEPROP 1 LAST PART_NUMBER CH4103K1B08
J 1
(-2700 1775);
DISPLAY 0.978723 (-2700 1775);
PAINT SKYBLUE (-2700 1775);
DISPLAY INVISIBLE (-2700 1775);
FORCEADD Q_CAP..2
(-3450 1675);
FORCEPROP 1 LAST LOCATION C1129
J 0
(-3750 1675);
DISPLAY 0.489362 (-3750 1675);
PAINT SKYBLUE (-3750 1675);
FORCEPROP 0 LAST $SEC 1
J 0
(-3075 1725);
DISPLAY 0.680851 (-3075 1725);
PAINT MONO (-3075 1725);
DISPLAY INVISIBLE (-3075 1725);
FORCEPROP 0 LAST CDS_SEC 1
J 0
(-3075 1725);
DISPLAY 1.021277 (-3075 1725);
DISPLAY INVISIBLE (-3075 1725);
FORCEPROP 1 LASTPIN (-3550 1675) $PN 1
J 0
(-3560 1690);
DISPLAY 0.489362 (-3560 1690);
PAINT MONO (-3560 1690);
FORCEPROP 1 LASTPIN (-3350 1675) $PN 2
J 0
(-3365 1690);
DISPLAY 0.489362 (-3365 1690);
PAINT MONO (-3365 1690);
FORCEPROP 1 LAST VALUE 0.1UF
J 2
(-3075 1675);
DISPLAY 0.489362 (-3075 1675);
PAINT SKYBLUE (-3075 1675);
FORCEPROP 1 LAST PACK_TYPE C0402
J 1
(-2600 1625);
DISPLAY 0.978723 (-2600 1625);
PAINT SKYBLUE (-2600 1625);
DISPLAY INVISIBLE (-2600 1625);
FORCEPROP 1 LAST VOLTAGE 16V
J 0
(-2925 1625);
DISPLAY 0.978723 (-2925 1625);
PAINT SKYBLUE (-2925 1625);
DISPLAY INVISIBLE (-2925 1625);
FORCEPROP 1 LAST TOLERANCE 10%
J 2
(-3175 1625);
DISPLAY 0.978723 (-3175 1625);
PAINT SKYBLUE (-3175 1625);
DISPLAY INVISIBLE (-3175 1625);
FORCEPROP 1 LAST MATERIAL X7R
J 0
(-3100 1625);
DISPLAY 0.978723 (-3100 1625);
PAINT SKYBLUE (-3100 1625);
DISPLAY INVISIBLE (-3100 1625);
FORCEPROP 2 LAST CDS_LIB pure_quanta
J 0
(-3450 1675);
DISPLAY INVISIBLE (-3450 1675);
FORCEPROP 1 LAST PATH I85
J 0
(-3450 1875);
DISPLAY 0.978723 (-3450 1875);
PAINT WHITE (-3450 1875);
DISPLAY INVISIBLE (-3450 1875);
FORCEPROP 1 LAST PART_NUMBER CH4103K1B08
J 1
(-2700 1675);
DISPLAY 0.978723 (-2700 1675);
PAINT SKYBLUE (-2700 1675);
DISPLAY INVISIBLE (-2700 1675);
FORCEADD Q_CAP..2
(-3450 1975);
FORCEPROP 1 LAST LOCATION C1126
J 0
(-3750 1975);
DISPLAY 0.489362 (-3750 1975);
PAINT SKYBLUE (-3750 1975);
FORCEPROP 0 LAST $SEC 1
J 0
(-2700 2025);
DISPLAY 0.680851 (-2700 2025);
PAINT MONO (-2700 2025);
DISPLAY INVISIBLE (-2700 2025);
FORCEPROP 0 LAST CDS_SEC 1
J 0
(-2700 2025);
DISPLAY 1.021277 (-2700 2025);
DISPLAY INVISIBLE (-2700 2025);
FORCEPROP 1 LASTPIN (-3550 1975) $PN 1
J 0
(-3560 1990);
DISPLAY 0.489362 (-3560 1990);
PAINT MONO (-3560 1990);
FORCEPROP 1 LASTPIN (-3350 1975) $PN 2
J 0
(-3365 1990);
DISPLAY 0.489362 (-3365 1990);
PAINT MONO (-3365 1990);
FORCEPROP 1 LAST MATERIAL X7R
J 0
(-3000 1975);
DISPLAY 0.489362 (-3000 1975);
PAINT SKYBLUE (-3000 1975);
FORCEPROP 1 LAST VALUE 0.1UF
J 2
(-3075 1975);
DISPLAY 0.489362 (-3075 1975);
PAINT SKYBLUE (-3075 1975);
FORCEPROP 1 LAST TOLERANCE 10%
J 2
(-2925 1950);
DISPLAY 0.489362 (-2925 1950);
PAINT SKYBLUE (-2925 1950);
FORCEPROP 1 LAST VOLTAGE 16V
J 0
(-2875 1950);
DISPLAY 0.489362 (-2875 1950);
PAINT SKYBLUE (-2875 1950);
FORCEPROP 1 LAST PACK_TYPE C0402
J 1
(-2700 1950);
DISPLAY 0.489362 (-2700 1950);
PAINT SKYBLUE (-2700 1950);
FORCEPROP 2 LAST CDS_LIB pure_quanta
J 0
(-3450 1975);
DISPLAY INVISIBLE (-3450 1975);
FORCEPROP 1 LAST PATH I86
J 0
(-3450 2175);
DISPLAY 0.978723 (-3450 2175);
PAINT WHITE (-3450 2175);
DISPLAY INVISIBLE (-3450 2175);
FORCEPROP 1 LAST PART_NUMBER CH4103K1B08
J 1
(-2750 1975);
DISPLAY 0.489362 (-2750 1975);
PAINT SKYBLUE (-2750 1975);
DISPLAY INVISIBLE (-2750 1975);
FORCEADD Q_CAP..2
(-3450 1875);
FORCEPROP 1 LAST LOCATION C1127
J 0
(-3750 1875);
DISPLAY 0.489362 (-3750 1875);
PAINT SKYBLUE (-3750 1875);
FORCEPROP 0 LAST $SEC 1
J 0
(-3075 1925);
DISPLAY 0.680851 (-3075 1925);
PAINT MONO (-3075 1925);
DISPLAY INVISIBLE (-3075 1925);
FORCEPROP 0 LAST CDS_SEC 1
J 0
(-3075 1925);
DISPLAY 1.021277 (-3075 1925);
DISPLAY INVISIBLE (-3075 1925);
FORCEPROP 1 LASTPIN (-3550 1875) $PN 1
J 0
(-3560 1890);
DISPLAY 0.489362 (-3560 1890);
PAINT MONO (-3560 1890);
FORCEPROP 1 LASTPIN (-3350 1875) $PN 2
J 0
(-3365 1890);
DISPLAY 0.489362 (-3365 1890);
PAINT MONO (-3365 1890);
FORCEPROP 1 LAST VALUE 0.1UF
J 2
(-3075 1875);
DISPLAY 0.489362 (-3075 1875);
PAINT SKYBLUE (-3075 1875);
FORCEPROP 1 LAST PACK_TYPE C0402
J 1
(-2600 1825);
DISPLAY 0.978723 (-2600 1825);
PAINT SKYBLUE (-2600 1825);
DISPLAY INVISIBLE (-2600 1825);
FORCEPROP 1 LAST VOLTAGE 16V
J 0
(-2925 1825);
DISPLAY 0.978723 (-2925 1825);
PAINT SKYBLUE (-2925 1825);
DISPLAY INVISIBLE (-2925 1825);
FORCEPROP 1 LAST TOLERANCE 10%
J 2
(-3175 1825);
DISPLAY 0.978723 (-3175 1825);
PAINT SKYBLUE (-3175 1825);
DISPLAY INVISIBLE (-3175 1825);
FORCEPROP 1 LAST MATERIAL X7R
J 0
(-3100 1825);
DISPLAY 0.978723 (-3100 1825);
PAINT SKYBLUE (-3100 1825);
DISPLAY INVISIBLE (-3100 1825);
FORCEPROP 2 LAST CDS_LIB pure_quanta
J 0
(-3450 1875);
DISPLAY INVISIBLE (-3450 1875);
FORCEPROP 1 LAST PATH I87
J 0
(-3450 2075);
DISPLAY 0.978723 (-3450 2075);
PAINT WHITE (-3450 2075);
DISPLAY INVISIBLE (-3450 2075);
FORCEPROP 1 LAST PART_NUMBER CH4103K1B08
J 1
(-2700 1875);
DISPLAY 0.978723 (-2700 1875);
PAINT SKYBLUE (-2700 1875);
DISPLAY INVISIBLE (-2700 1875);
FORCEADD GND..1
(-2100 675);
FORCEPROP 3 LASTPIN (-2100 725) SIG_NAME GND\g
J 0
(-2090 735);
DISPLAY 0.659574 (-2090 735);
PAINT MONO (-2090 735);
DISPLAY INVISIBLE (-2090 735);
FORCEPROP 2 LAST CDS_LIB pure_quanta_power
J 0
(-2100 675);
DISPLAY INVISIBLE (-2100 675);
FORCEPROP 1 LAST SIZE 1B
J 0
(-2025 625);
DISPLAY 0.851064 (-2025 625);
PAINT GREEN (-2025 625);
DISPLAY INVISIBLE (-2025 625);
FORCEPROP 2 LAST BOM_COST MEM
J 0
(-2200 750);
DISPLAY 0.808511 (-2200 750);
DISPLAY INVISIBLE (-2200 750);
FORCEPROP 1 LAST HDL_POWER GND
J 0
(-2100 825);
DISPLAY 0.851064 (-2100 825);
PAINT GREEN (-2100 825);
DISPLAY INVISIBLE (-2100 825);
FORCEPROP 1 LAST PATH I88
J 0
(-2025 675);
DISPLAY 0.872340 (-2025 675);
PAINT AQUA (-2025 675);
DISPLAY INVISIBLE (-2025 675);
FORCEADD VCC_CORE..1
(-3825 2150);
FORCEPROP 3 LASTPIN (-3825 2100) SIG_NAME P1V8_AUX\g
J 0
(-3815 2110);
DISPLAY 0.659574 (-3815 2110);
PAINT MONO (-3815 2110);
DISPLAY INVISIBLE (-3815 2110);
FORCEPROP 1 LAST HDL_POWER P1V8_AUX
J 1
(-3825 2200);
DISPLAY 0.489362 (-3825 2200);
PAINT GREEN (-3825 2200);
FORCEPROP 2 LAST CDS_LIB pure_quanta_power
J 0
(-3825 2150);
DISPLAY INVISIBLE (-3825 2150);
FORCEPROP 1 LAST PATH I89
J 0
(-3775 2175);
DISPLAY 0.872340 (-3775 2175);
PAINT AQUA (-3775 2175);
DISPLAY INVISIBLE (-3775 2175);
FORCEADD OFFPAGE..5
(-8225 3825);
FORCEPROP 2 LAST $XR3 142 
J 0
(-8809 3825);
DISPLAY 0.638298 (-8809 3825);
PAINT MONO (-8809 3825);
FORCEPROP 2 LAST $XR2 141 
J 0
(-8689 3825);
DISPLAY 0.638298 (-8689 3825);
PAINT MONO (-8689 3825);
FORCEPROP 2 LAST $XR1 140 
J 0
(-8569 3825);
DISPLAY 0.638298 (-8569 3825);
PAINT MONO (-8569 3825);
FORCEPROP 2 LAST $XR0 81 
J 0
(-8449 3825);
DISPLAY 0.638298 (-8449 3825);
PAINT MONO (-8449 3825);
FORCEPROP 2 LAST CDS_LIB standard
J 0
(-8225 3825);
DISPLAY INVISIBLE (-8225 3825);
FORCEPROP 1 LAST OFFPAGE TRUE
J 0
(-7900 3700);
DISPLAY 0.872340 (-7900 3700);
PAINT GREEN (-7900 3700);
DISPLAY INVISIBLE (-7900 3700);
FORCEPROP 1 LAST COMMENT_BODY TRUE
J 0
(-8125 3750);
DISPLAY 0.872340 (-8125 3750);
PAINT GREEN (-8125 3750);
DISPLAY INVISIBLE (-8125 3750);
FORCEPROP 2 LAST PATH I9
J 0
(-8475 3875);
DISPLAY 0.680851 (-8475 3875);
DISPLAY INVISIBLE (-8475 3875);
FORCEADD GND..1
(-3700 3025);
FORCEPROP 3 LASTPIN (-3700 3075) SIG_NAME GND\g
J 0
(-3690 3085);
DISPLAY 0.659574 (-3690 3085);
PAINT MONO (-3690 3085);
DISPLAY INVISIBLE (-3690 3085);
FORCEPROP 2 LAST CDS_LIB pure_quanta_power
J 0
(-3700 3025);
DISPLAY INVISIBLE (-3700 3025);
FORCEPROP 2 LAST BOM_COST MEM
J 0
(-3800 3100);
DISPLAY 0.808511 (-3800 3100);
DISPLAY INVISIBLE (-3800 3100);
FORCEPROP 1 LAST SIZE 1B
J 0
(-3625 2975);
DISPLAY 0.851064 (-3625 2975);
PAINT GREEN (-3625 2975);
DISPLAY INVISIBLE (-3625 2975);
FORCEPROP 1 LAST HDL_POWER GND
J 0
(-3700 3175);
DISPLAY 0.851064 (-3700 3175);
PAINT GREEN (-3700 3175);
DISPLAY INVISIBLE (-3700 3175);
FORCEPROP 1 LAST PATH I90
J 0
(-3625 3025);
DISPLAY 0.872340 (-3625 3025);
PAINT AQUA (-3625 3025);
DISPLAY INVISIBLE (-3625 3025);
FORCEADD GND..1
(-3500 3025);
FORCEPROP 3 LASTPIN (-3500 3075) SIG_NAME GND\g
J 0
(-3490 3085);
DISPLAY 0.659574 (-3490 3085);
PAINT MONO (-3490 3085);
DISPLAY INVISIBLE (-3490 3085);
FORCEPROP 2 LAST CDS_LIB pure_quanta_power
J 0
(-3500 3025);
DISPLAY INVISIBLE (-3500 3025);
FORCEPROP 1 LAST SIZE 1B
J 0
(-3425 2975);
DISPLAY 0.851064 (-3425 2975);
PAINT GREEN (-3425 2975);
DISPLAY INVISIBLE (-3425 2975);
FORCEPROP 2 LAST BOM_COST MEM
J 0
(-3600 3100);
DISPLAY 0.808511 (-3600 3100);
DISPLAY INVISIBLE (-3600 3100);
FORCEPROP 1 LAST HDL_POWER GND
J 0
(-3500 3175);
DISPLAY 0.851064 (-3500 3175);
PAINT GREEN (-3500 3175);
DISPLAY INVISIBLE (-3500 3175);
FORCEPROP 1 LAST PATH I91
J 0
(-3425 3025);
DISPLAY 0.872340 (-3425 3025);
PAINT AQUA (-3425 3025);
DISPLAY INVISIBLE (-3425 3025);
FORCEADD GND..1
(-3300 3025);
FORCEPROP 3 LASTPIN (-3300 3075) SIG_NAME GND\g
J 0
(-3290 3085);
DISPLAY 0.659574 (-3290 3085);
PAINT MONO (-3290 3085);
DISPLAY INVISIBLE (-3290 3085);
FORCEPROP 2 LAST CDS_LIB pure_quanta_power
J 0
(-3300 3025);
DISPLAY INVISIBLE (-3300 3025);
FORCEPROP 2 LAST BOM_COST MEM
J 0
(-3400 3100);
DISPLAY 0.808511 (-3400 3100);
DISPLAY INVISIBLE (-3400 3100);
FORCEPROP 1 LAST SIZE 1B
J 0
(-3225 2975);
DISPLAY 0.851064 (-3225 2975);
PAINT GREEN (-3225 2975);
DISPLAY INVISIBLE (-3225 2975);
FORCEPROP 1 LAST HDL_POWER GND
J 0
(-3300 3175);
DISPLAY 0.851064 (-3300 3175);
PAINT GREEN (-3300 3175);
DISPLAY INVISIBLE (-3300 3175);
FORCEPROP 1 LAST PATH I92
J 0
(-3225 3025);
DISPLAY 0.872340 (-3225 3025);
PAINT AQUA (-3225 3025);
DISPLAY INVISIBLE (-3225 3025);
FORCEADD Q_RES..2
(-3700 3250);
FORCEPROP 1 LAST LOCATION R10
J 0
(-3675 3375);
DISPLAY 0.489362 (-3675 3375);
PAINT SKYBLUE (-3675 3375);
FORCEPROP 0 LAST $SEC 1
J 0
(-3650 3425);
DISPLAY 0.680851 (-3650 3425);
PAINT MONO (-3650 3425);
DISPLAY INVISIBLE (-3650 3425);
FORCEPROP 0 LAST CDS_SEC 1
J 0
(-3650 3425);
DISPLAY 1.021277 (-3650 3425);
DISPLAY INVISIBLE (-3650 3425);
FORCEPROP 1 LASTPIN (-3700 3350) $PN 1
J 0
(-3695 3312);
DISPLAY 0.489362 (-3695 3312);
PAINT MONO (-3695 3312);
FORCEPROP 1 LASTPIN (-3700 3150) $PN 2
J 0
(-3695 3160);
DISPLAY 0.489362 (-3695 3160);
PAINT MONO (-3695 3160);
FORCEPROP 1 LAST WATTAGE 1/16W
J 0
(-3660 3225);
DISPLAY 0.489362 (-3660 3225);
PAINT SKYBLUE (-3660 3225);
FORCEPROP 1 LAST PACK_TYPE 0402LF
J 0
(-3650 3125);
DISPLAY 0.489362 (-3650 3125);
PAINT SKYBLUE (-3650 3125);
FORCEPROP 1 LAST TOLERANCE 1%
J 0
(-3655 3275);
DISPLAY 0.489362 (-3655 3275);
PAINT SKYBLUE (-3655 3275);
FORCEPROP 1 LAST VALUE 10K
J 0
(-3655 3325);
DISPLAY 0.489362 (-3655 3325);
PAINT SKYBLUE (-3655 3325);
FORCEPROP 1 LAST MATERIAL CHIP
J 0
(-3660 3175);
DISPLAY 0.489362 (-3660 3175);
PAINT SKYBLUE (-3660 3175);
FORCEPROP 2 LAST CDS_LIB pure_quanta
J 0
(-3700 3250);
DISPLAY INVISIBLE (-3700 3250);
FORCEPROP 2 LAST BOM_COST MEM
J 0
(-3650 3425);
DISPLAY 0.808511 (-3650 3425);
DISPLAY INVISIBLE (-3650 3425);
FORCEPROP 1 LAST PATH I93
J 0
(-3650 3425);
DISPLAY 0.978723 (-3650 3425);
PAINT WHITE (-3650 3425);
DISPLAY INVISIBLE (-3650 3425);
FORCEPROP 1 LAST PART_NUMBER CS31002FB08
J 0
(-3660 3125);
DISPLAY 0.489362 (-3660 3125);
PAINT SKYBLUE (-3660 3125);
DISPLAY INVISIBLE (-3660 3125);
FORCEADD Q_RES..2
(-3500 3250);
FORCEPROP 1 LAST LOCATION R11
J 0
(-3475 3375);
DISPLAY 0.489362 (-3475 3375);
PAINT SKYBLUE (-3475 3375);
FORCEPROP 0 LAST $SEC 1
J 0
(-3450 3425);
DISPLAY 0.680851 (-3450 3425);
PAINT MONO (-3450 3425);
DISPLAY INVISIBLE (-3450 3425);
FORCEPROP 0 LAST CDS_SEC 1
J 0
(-3450 3425);
DISPLAY 1.021277 (-3450 3425);
DISPLAY INVISIBLE (-3450 3425);
FORCEPROP 1 LASTPIN (-3500 3350) $PN 1
J 0
(-3495 3312);
DISPLAY 0.489362 (-3495 3312);
PAINT MONO (-3495 3312);
FORCEPROP 1 LASTPIN (-3500 3150) $PN 2
J 0
(-3495 3160);
DISPLAY 0.489362 (-3495 3160);
PAINT MONO (-3495 3160);
FORCEPROP 1 LAST VALUE 10K
J 0
(-3455 3325);
DISPLAY 0.489362 (-3455 3325);
PAINT SKYBLUE (-3455 3325);
FORCEPROP 1 LAST PACK_TYPE 0402LF
J 0
(-3450 3125);
DISPLAY 0.489362 (-3450 3125);
PAINT SKYBLUE (-3450 3125);
FORCEPROP 1 LAST TOLERANCE 1%
J 0
(-3455 3275);
DISPLAY 0.489362 (-3455 3275);
PAINT SKYBLUE (-3455 3275);
FORCEPROP 1 LAST MATERIAL CHIP
J 0
(-3460 3175);
DISPLAY 0.489362 (-3460 3175);
PAINT SKYBLUE (-3460 3175);
FORCEPROP 1 LAST WATTAGE 1/16W
J 0
(-3460 3225);
DISPLAY 0.489362 (-3460 3225);
PAINT SKYBLUE (-3460 3225);
FORCEPROP 2 LAST CDS_LIB pure_quanta
J 0
(-3500 3250);
DISPLAY INVISIBLE (-3500 3250);
FORCEPROP 2 LAST BOM_COST MEM
J 0
(-3450 3425);
DISPLAY 0.808511 (-3450 3425);
DISPLAY INVISIBLE (-3450 3425);
FORCEPROP 1 LAST PATH I94
J 0
(-3450 3425);
DISPLAY 0.978723 (-3450 3425);
PAINT WHITE (-3450 3425);
DISPLAY INVISIBLE (-3450 3425);
FORCEPROP 1 LAST PART_NUMBER CS31002FB08
J 0
(-3460 3125);
DISPLAY 0.489362 (-3460 3125);
PAINT SKYBLUE (-3460 3125);
DISPLAY INVISIBLE (-3460 3125);
FORCEADD Q_RES..2
(-3300 3250);
FORCEPROP 1 LAST LOCATION R12
J 0
(-3275 3375);
DISPLAY 0.489362 (-3275 3375);
PAINT SKYBLUE (-3275 3375);
FORCEPROP 0 LAST $SEC 1
J 0
(-3250 3425);
DISPLAY 0.680851 (-3250 3425);
PAINT MONO (-3250 3425);
DISPLAY INVISIBLE (-3250 3425);
FORCEPROP 0 LAST CDS_SEC 1
J 0
(-3250 3425);
DISPLAY 1.021277 (-3250 3425);
DISPLAY INVISIBLE (-3250 3425);
FORCEPROP 1 LASTPIN (-3300 3350) $PN 1
J 0
(-3295 3312);
DISPLAY 0.489362 (-3295 3312);
PAINT MONO (-3295 3312);
FORCEPROP 1 LASTPIN (-3300 3150) $PN 2
J 0
(-3295 3160);
DISPLAY 0.489362 (-3295 3160);
PAINT MONO (-3295 3160);
FORCEPROP 1 LAST PACK_TYPE 0402LF
J 0
(-3250 3125);
DISPLAY 0.489362 (-3250 3125);
PAINT SKYBLUE (-3250 3125);
FORCEPROP 1 LAST WATTAGE 1/16W
J 0
(-3260 3225);
DISPLAY 0.489362 (-3260 3225);
PAINT SKYBLUE (-3260 3225);
FORCEPROP 1 LAST MATERIAL CHIP
J 0
(-3260 3175);
DISPLAY 0.489362 (-3260 3175);
PAINT SKYBLUE (-3260 3175);
FORCEPROP 1 LAST VALUE 10K
J 0
(-3255 3325);
DISPLAY 0.489362 (-3255 3325);
PAINT SKYBLUE (-3255 3325);
FORCEPROP 1 LAST TOLERANCE 1%
J 0
(-3255 3275);
DISPLAY 0.489362 (-3255 3275);
PAINT SKYBLUE (-3255 3275);
FORCEPROP 2 LAST CDS_LIB pure_quanta
J 0
(-3300 3250);
DISPLAY INVISIBLE (-3300 3250);
FORCEPROP 2 LAST BOM_COST MEM
J 0
(-3250 3425);
DISPLAY 0.808511 (-3250 3425);
DISPLAY INVISIBLE (-3250 3425);
FORCEPROP 1 LAST PATH I95
J 0
(-3250 3425);
DISPLAY 0.978723 (-3250 3425);
PAINT WHITE (-3250 3425);
DISPLAY INVISIBLE (-3250 3425);
FORCEPROP 1 LAST PART_NUMBER CS31002FB08
J 0
(-3260 3125);
DISPLAY 0.489362 (-3260 3125);
PAINT SKYBLUE (-3260 3125);
DISPLAY INVISIBLE (-3260 3125);
FORCEADD GND..1
(-3075 3025);
FORCEPROP 3 LASTPIN (-3075 3075) SIG_NAME GND\g
J 0
(-3065 3085);
DISPLAY 0.659574 (-3065 3085);
PAINT MONO (-3065 3085);
DISPLAY INVISIBLE (-3065 3085);
FORCEPROP 2 LAST CDS_LIB pure_quanta_power
J 0
(-3075 3025);
DISPLAY INVISIBLE (-3075 3025);
FORCEPROP 1 LAST SIZE 1B
J 0
(-3000 2975);
DISPLAY 0.851064 (-3000 2975);
PAINT GREEN (-3000 2975);
DISPLAY INVISIBLE (-3000 2975);
FORCEPROP 2 LAST BOM_COST MEM
J 0
(-3175 3100);
DISPLAY 0.808511 (-3175 3100);
DISPLAY INVISIBLE (-3175 3100);
FORCEPROP 1 LAST HDL_POWER GND
J 0
(-3075 3175);
DISPLAY 0.851064 (-3075 3175);
PAINT GREEN (-3075 3175);
DISPLAY INVISIBLE (-3075 3175);
FORCEPROP 1 LAST PATH I96
J 0
(-3000 3025);
DISPLAY 0.872340 (-3000 3025);
PAINT AQUA (-3000 3025);
DISPLAY INVISIBLE (-3000 3025);
FORCEADD Q_RES..2
(-3075 3250);
FORCEPROP 1 LAST LOCATION R25
J 0
(-3050 3375);
DISPLAY 0.489362 (-3050 3375);
PAINT SKYBLUE (-3050 3375);
FORCEPROP 0 LAST $SEC 1
J 0
(-3025 3425);
DISPLAY 0.680851 (-3025 3425);
PAINT MONO (-3025 3425);
DISPLAY INVISIBLE (-3025 3425);
FORCEPROP 0 LAST CDS_SEC 1
J 0
(-3025 3425);
DISPLAY 1.021277 (-3025 3425);
DISPLAY INVISIBLE (-3025 3425);
FORCEPROP 1 LASTPIN (-3075 3350) $PN 1
J 0
(-3070 3312);
DISPLAY 0.489362 (-3070 3312);
PAINT MONO (-3070 3312);
FORCEPROP 1 LASTPIN (-3075 3150) $PN 2
J 0
(-3070 3160);
DISPLAY 0.489362 (-3070 3160);
PAINT MONO (-3070 3160);
FORCEPROP 1 LAST PACK_TYPE 0402LF
J 0
(-3025 3125);
DISPLAY 0.489362 (-3025 3125);
PAINT SKYBLUE (-3025 3125);
FORCEPROP 1 LAST WATTAGE 1/16W
J 0
(-3035 3225);
DISPLAY 0.489362 (-3035 3225);
PAINT SKYBLUE (-3035 3225);
FORCEPROP 1 LAST TOLERANCE 1%
J 0
(-3030 3275);
DISPLAY 0.489362 (-3030 3275);
PAINT SKYBLUE (-3030 3275);
FORCEPROP 1 LAST MATERIAL CHIP
J 0
(-3035 3175);
DISPLAY 0.489362 (-3035 3175);
PAINT SKYBLUE (-3035 3175);
FORCEPROP 1 LAST VALUE 10K
J 0
(-3030 3325);
DISPLAY 0.489362 (-3030 3325);
PAINT SKYBLUE (-3030 3325);
FORCEPROP 2 LAST BOM_COST MEM
J 0
(-3025 3425);
DISPLAY 0.808511 (-3025 3425);
DISPLAY INVISIBLE (-3025 3425);
FORCEPROP 2 LAST CDS_LIB pure_quanta
J 0
(-3075 3250);
DISPLAY INVISIBLE (-3075 3250);
FORCEPROP 1 LAST PATH I97
J 0
(-3025 3425);
DISPLAY 0.978723 (-3025 3425);
PAINT WHITE (-3025 3425);
DISPLAY INVISIBLE (-3025 3425);
FORCEPROP 1 LAST PART_NUMBER CS31002FB08
J 0
(-3035 3125);
DISPLAY 0.489362 (-3035 3125);
PAINT SKYBLUE (-3035 3125);
DISPLAY INVISIBLE (-3035 3125);
FORCEADD OFFPAGE..1
R 2
(-2225 3525);
FORCEPROP 2 LAST $XR1 159 
J 0
(-1949 3525);
DISPLAY 0.638298 (-1949 3525);
PAINT MONO (-1949 3525);
FORCEPROP 2 LAST $XR0 80 
J 0
(-2039 3525);
DISPLAY 0.638298 (-2039 3525);
PAINT MONO (-2039 3525);
FORCEPROP 2 LAST CDS_LIB standard
J 0
(-2225 3525);
DISPLAY INVISIBLE (-2225 3525);
FORCEPROP 1 LAST OFFPAGE TRUE
J 2
(-2550 3400);
DISPLAY 0.872340 (-2550 3400);
PAINT GREEN (-2550 3400);
DISPLAY INVISIBLE (-2550 3400);
FORCEPROP 1 LAST COMMENT_BODY TRUE
J 2
(-2350 3425);
DISPLAY 0.872340 (-2350 3425);
PAINT GREEN (-2350 3425);
DISPLAY INVISIBLE (-2350 3425);
FORCEPROP 2 LAST PATH I98
J 0
(-1925 3575);
DISPLAY 0.680851 (-1925 3575);
DISPLAY INVISIBLE (-1925 3575);
FORCEADD OFFPAGE..1
R 2
(-2225 3575);
FORCEPROP 2 LAST $XR1 159 
J 0
(-1949 3575);
DISPLAY 0.638298 (-1949 3575);
PAINT MONO (-1949 3575);
FORCEPROP 2 LAST $XR0 80 
J 0
(-2039 3575);
DISPLAY 0.638298 (-2039 3575);
PAINT MONO (-2039 3575);
FORCEPROP 2 LAST CDS_LIB standard
J 0
(-2225 3575);
DISPLAY INVISIBLE (-2225 3575);
FORCEPROP 1 LAST OFFPAGE TRUE
J 2
(-2550 3450);
DISPLAY 0.872340 (-2550 3450);
PAINT GREEN (-2550 3450);
DISPLAY INVISIBLE (-2550 3450);
FORCEPROP 1 LAST COMMENT_BODY TRUE
J 2
(-2350 3475);
DISPLAY 0.872340 (-2350 3475);
PAINT GREEN (-2350 3475);
DISPLAY INVISIBLE (-2350 3475);
FORCEPROP 2 LAST PATH I99
J 0
(-1925 3625);
DISPLAY 0.680851 (-1925 3625);
DISPLAY INVISIBLE (-1925 3625);
FORCEADD DNS..2
(-7050 2975);
PAINT RED (-7050 2975);
FORCEPROP 2 LAST CDS_LIB mstr_misc
J 0
(-7050 2975);
DISPLAY INVISIBLE (-7050 2975);
FORCEPROP 1 LAST COMMENT_BODY TRUE
R 1
J 0
(-6975 2750);
DISPLAY 0.872340 (-6975 2750);
PAINT PEACH (-6975 2750);
DISPLAY INVISIBLE (-6975 2750);
FORCEADD DNS..2
(-6950 3600);
PAINT RED (-6950 3600);
FORCEPROP 2 LAST CDS_LIB mstr_misc
J 0
(-6950 3600);
DISPLAY INVISIBLE (-6950 3600);
FORCEPROP 1 LAST COMMENT_BODY TRUE
R 1
J 0
(-6875 3375);
DISPLAY 0.872340 (-6875 3375);
PAINT PEACH (-6875 3375);
DISPLAY INVISIBLE (-6875 3375);
FORCEADD DNS..2
(-3975 3225);
PAINT RED (-3975 3225);
FORCEPROP 2 LAST CDS_LIB mstr_misc
J 0
(-3975 3225);
DISPLAY INVISIBLE (-3975 3225);
FORCEPROP 1 LAST COMMENT_BODY TRUE
R 1
J 0
(-3900 3000);
DISPLAY 0.872340 (-3900 3000);
PAINT PEACH (-3900 3000);
DISPLAY INVISIBLE (-3900 3000);
FORCEADD DNS..2
(-2600 3200);
PAINT RED (-2600 3200);
FORCEPROP 2 LAST CDS_LIB mstr_misc
J 0
(-2600 3200);
DISPLAY INVISIBLE (-2600 3200);
FORCEPROP 1 LAST COMMENT_BODY TRUE
R 1
J 0
(-2525 2975);
DISPLAY 0.872340 (-2525 2975);
PAINT PEACH (-2525 2975);
DISPLAY INVISIBLE (-2525 2975);
FORCEADD DNS..2
(-7050 4150);
PAINT RED (-7050 4150);
FORCEPROP 2 LAST CDS_LIB mstr_misc
J 0
(-7050 4150);
DISPLAY INVISIBLE (-7050 4150);
FORCEPROP 1 LAST COMMENT_BODY TRUE
R 1
J 0
(-6975 3925);
DISPLAY 0.872340 (-6975 3925);
PAINT PEACH (-6975 3925);
DISPLAY INVISIBLE (-6975 3925);
FORCEADD QUANTA_TITLE_BLOCK_C..1
(0 0);
FORCEPROP 0 LAST CDS_CON_LAST_MODIFIED Thu Sep 14 16:12:38 2023
J 0
(-1885 15);
DISPLAY INVISIBLE (-1885 15);
FORCEPROP 1 LAST CUSTOM_TXT_CDS <CON_LAST_MODIFIED>
J 0
(-1885 15);
DISPLAY 0.978723 (-1885 15);
FORCEPROP 2 LAST CUSTOM_TXT_CDS <XR_PAGE_TITLE>
J 0
(-7890 5250);
DISPLAY 0.638298 (-7890 5250);
PAINT PINK (-7890 5250);
DISPLAY INVISIBLE (-7890 5250);
FORCEPROP 1 LAST CUSTOM_TXT_CDS <NAME_2>
J 0
(-3175 50);
FORCEPROP 1 LAST CUSTOM_TXT_CDS <NAME_1>
J 0
(-3175 175);
FORCEPROP 1 LAST CUSTOM_TXT_CDS <Q_NUMBER>
J 0
(-1403 103);
DISPLAY 1.212766 (-1403 103);
FORCEPROP 1 LAST CUSTOM_TXT_CDS <Q_PROJ>
J 0
(-2382 102);
DISPLAY 1.212766 (-2382 102);
FORCEPROP 1 LAST CUSTOM_TXT_CDS <Q_REV>
J 0
(-184 103);
DISPLAY 1.212766 (-184 103);
FORCEPROP 1 LAST CUSTOM_TXT_CDS <CON_PAGE_NUM> OF <CON_TOTAL_PAGES>
J 0
(-446 18);
DISPLAY 0.978723 (-446 18);
FORCEPROP 1 LAST Q_TITLE FPGA 4/6
J 0
(-9300 50);
DISPLAY 2.446809 (-9300 50);
PAINT GREEN (-9300 50);
FORCEPROP 2 LAST PAGE_BORDER TRUE
J 0
(-7890 5250);
DISPLAY 0.638298 (-7890 5250);
PAINT PINK (-7890 5250);
DISPLAY INVISIBLE (-7890 5250);
FORCEPROP 1 LAST CDS_LMAN_SYM_OUTLINE -9475,6775,100,-125
J 0
(0 0);
DISPLAY 0.468085 (0 0);
PAINT GREEN (0 0);
DISPLAY INVISIBLE (0 0);
FORCEPROP 2 LAST CDS_LIB pure_quanta
J 0
(0 0);
DISPLAY INVISIBLE (0 0);
FORCEPROP 2 LAST CDS_XR_PAGE_TITLE CR-83 : @T6G_MB_LIB.T6G(SCH_1):PAGE83
J 0
(-7890 5250);
DISPLAY 0.638298 (-7890 5250);
PAINT PINK (-7890 5250);
DISPLAY INVISIBLE (-7890 5250);
FORCEPROP 1 LAST Q_DEPT BU9
J 1
(-3763 49);
DISPLAY 1.957447 (-3763 49);
PAINT GREEN (-3763 49);
DISPLAY INVISIBLE (-3763 49);
FORCEPROP 1 LAST COMMENT_BODY TRUE
J 0
(12 -13);
DISPLAY 0.978723 (12 -13);
PAINT GREEN (12 -13);
DISPLAY INVISIBLE (12 -13);
FORCEADD CAD_NOTE..1
(-3350 2400);
FORCEPROP 0 LAST L1 NEAR CPLD
J 0
(-3500 2275);
DISPLAY 0.617021 (-3500 2275);
PAINT WHITE (-3500 2275);
FORCEPROP 2 LAST CDS_LIB pure_quanta_power
J 0
(-3350 2400);
DISPLAY INVISIBLE (-3350 2400);
FORCEPROP 1 LAST COMMENT_BODY TRUE
J 0
(-3325 2500);
DISPLAY 0.574468 (-3325 2500);
PAINT WHITE (-3325 2500);
DISPLAY INVISIBLE (-3325 2500);
FORCEADD CAD_NOTE..1
(-1025 2375);
FORCEPROP 0 LAST L1 NEAR CPLD
J 0
(-1175 2250);
DISPLAY 0.617021 (-1175 2250);
PAINT WHITE (-1175 2250);
FORCEPROP 2 LAST CDS_LIB pure_quanta_power
J 0
(-1025 2375);
DISPLAY INVISIBLE (-1025 2375);
FORCEPROP 1 LAST COMMENT_BODY TRUE
J 0
(-1000 2475);
DISPLAY 0.574468 (-1000 2475);
PAINT WHITE (-1000 2475);
DISPLAY INVISIBLE (-1000 2475);
FORCEADD DNS..2
(-7050 3800);
PAINT RED (-7050 3800);
FORCEPROP 2 LAST CDS_LIB mstr_misc
J 0
(-7050 3800);
DISPLAY INVISIBLE (-7050 3800);
FORCEPROP 1 LAST COMMENT_BODY TRUE
R 1
J 0
(-6975 3575);
DISPLAY 0.872340 (-6975 3575);
PAINT PEACH (-6975 3575);
DISPLAY INVISIBLE (-6975 3575);
FORCEADD DNS..2
(-7050 3750);
PAINT RED (-7050 3750);
FORCEPROP 2 LAST CDS_LIB mstr_misc
J 0
(-7050 3750);
DISPLAY INVISIBLE (-7050 3750);
FORCEPROP 1 LAST COMMENT_BODY TRUE
R 1
J 0
(-6975 3525);
DISPLAY 0.872340 (-6975 3525);
PAINT PEACH (-6975 3525);
DISPLAY INVISIBLE (-6975 3525);
FORCEADD DNS..2
(-7025 3925);
PAINT RED (-7025 3925);
FORCEPROP 2 LAST CDS_LIB mstr_misc
J 0
(-7025 3925);
DISPLAY INVISIBLE (-7025 3925);
FORCEPROP 1 LAST COMMENT_BODY TRUE
R 1
J 0
(-6950 3700);
DISPLAY 0.872340 (-6950 3700);
PAINT PEACH (-6950 3700);
DISPLAY INVISIBLE (-6950 3700);
FORCEADD DNS..2
(-7075 5125);
PAINT RED (-7075 5125);
FORCEPROP 2 LAST CDS_LIB mstr_misc
J 0
(-7075 5125);
DISPLAY INVISIBLE (-7075 5125);
FORCEPROP 1 LAST COMMENT_BODY TRUE
R 1
J 0
(-7000 4900);
DISPLAY 0.872340 (-7000 4900);
PAINT PEACH (-7000 4900);
DISPLAY INVISIBLE (-7000 4900);
FORCEADD DNS..2
(-7075 4875);
PAINT RED (-7075 4875);
FORCEPROP 2 LAST CDS_LIB mstr_misc
J 0
(-7075 4875);
DISPLAY INVISIBLE (-7075 4875);
FORCEPROP 1 LAST COMMENT_BODY TRUE
R 1
J 0
(-7000 4650);
DISPLAY 0.872340 (-7000 4650);
PAINT PEACH (-7000 4650);
DISPLAY INVISIBLE (-7000 4650);
WIRE 16 -1 (-3625 4300)(-3625 4375);
WIRE 16 -1 (-3425 4300)(-3425 4375);
WIRE 16 -1 (-3500 5625)(-3500 5700);
WIRE 16 -1 (-3300 5625)(-3300 5700);
WIRE 16 -1 (-3100 5625)(-3100 5700);
WIRE 16 -1 (-2875 5625)(-2875 5700);
WIRE 16 -1 (-2875 3150)(-2875 3050);
WIRE 16 -1 (-2675 3025)(-2675 3125);
WIRE 16 -1 (-4050 3050)(-4050 3150);
WIRE 16 -1 (-4250 3150)(-4250 3050);
WIRE 16 -1 (-4475 3175)(-4475 3050);
WIRE 16 -1 (-3700 3075)(-3700 3150);
WIRE 16 -1 (-3500 3075)(-3500 3150);
WIRE 16 -1 (-3300 3075)(-3300 3150);
WIRE 16 -1 (-3075 3075)(-3075 3150);
WIRE 16 -1 (-7175 3000)(-8175 3000);
FORCEPROP 2 LAST SIG_NAME SCM_SYS_PWRBTN_N
J 0
(-8050 3010);
DISPLAY 0.489362 (-8050 3010);
WIRE 16 -1 (-8150 4875)(-7150 4875);
FORCEPROP 2 LAST SIG_NAME FM_APML_MUX2_SEL
J 0
(-8085 4885);
DISPLAY 0.680851 (-8085 4885);
WIRE 16 -1 (-8150 4575)(-7150 4575);
FORCEPROP 0 LAST SIG_NAME E1S_0_PRSNT_N
J 0
(-8060 4585);
DISPLAY 0.489362 (-8060 4585);
WIRE 16 -1 (-6800 3600)(-6800 3650);
WIRE 16 -1 (-6800 3600)(-6950 3600);
WIRE 16 -1 (-6800 3775)(-6800 3650);
WIRE 16 -1 (-6800 3650)(-6950 3650);
WIRE 16 -1 (-6800 3825)(-6800 3775);
WIRE 16 -1 (-6950 3775)(-6800 3775);
WIRE 16 -1 (-6800 3950)(-6800 3825);
WIRE 16 -1 (-6950 3825)(-6800 3825);
WIRE 16 -1 (-6800 3950)(-6800 4200);
WIRE 16 -1 (-6800 3950)(-6950 3950);
WIRE 16 -1 (-6800 4325)(-6800 4200);
WIRE 16 -1 (-6950 4200)(-6800 4200);
WIRE 16 -1 (-6800 4575)(-6800 4325);
WIRE 16 -1 (-6800 4325)(-6950 4325);
WIRE 16 -1 (-6800 4575)(-6800 4875);
WIRE 16 -1 (-6800 4575)(-6950 4575);
WIRE 16 -1 (-6800 4875)(-6800 4925);
WIRE 16 -1 (-6950 4875)(-6800 4875);
WIRE 16 -1 (-6800 4925)(-6800 5125);
WIRE 16 -1 (-6950 4925)(-6800 4925);
WIRE 16 -1 (-6800 5175)(-6800 5125);
WIRE 16 -1 (-6950 5125)(-6800 5125);
WIRE 16 -1 (-6800 5250)(-6800 5175);
WIRE 16 -1 (-6950 5175)(-6800 5175);
WIRE 16 -1 (-6800 5325)(-6800 5250);
WIRE 16 -1 (-6950 5250)(-6800 5250);
WIRE 16 -1 (-6800 5325)(-6800 5375);
WIRE 16 -1 (-6800 5325)(-6950 5325);
WIRE 16 -1 (-6800 5425)(-6800 5375);
WIRE 16 -1 (-6800 5375)(-6950 5375);
WIRE 16 -1 (-6800 5425)(-6800 5475);
WIRE 16 -1 (-6800 5425)(-6950 5425);
WIRE 16 -1 (-6800 5525)(-6800 5475);
WIRE 16 -1 (-6800 5475)(-6950 5475);
WIRE 16 -1 (-6800 5575)(-6800 5525);
WIRE 16 -1 (-6800 5525)(-6950 5525);
WIRE 16 -1 (-6800 5600)(-6800 5575);
WIRE 16 -1 (-6800 5575)(-6950 5575);
WIRE 16 -1 (-1100 1825)(-375 1825);
WIRE 16 -1 (-375 1825)(-375 1725);
WIRE 16 -1 (-375 1725)(-375 1625);
WIRE 16 -1 (-1100 1725)(-375 1725);
WIRE 16 -1 (-375 1525)(-375 1625);
WIRE 16 -1 (-1100 1625)(-375 1625);
WIRE 16 -1 (-375 1425)(-375 1525);
WIRE 16 -1 (-1100 1525)(-375 1525);
WIRE 16 -1 (-375 1325)(-375 1425);
WIRE 16 -1 (-1100 1425)(-375 1425);
WIRE 16 -1 (-375 1225)(-375 1325);
WIRE 16 -1 (-1100 1325)(-375 1325);
WIRE 16 -1 (-375 1125)(-375 1225);
WIRE 16 -1 (-1100 1225)(-375 1225);
WIRE 16 -1 (-375 1025)(-375 1125);
WIRE 16 -1 (-1100 1125)(-375 1125);
WIRE 16 -1 (-375 1025)(-375 925);
WIRE 16 -1 (-1100 1025)(-375 1025);
WIRE 16 -1 (-375 825)(-375 925);
WIRE 16 -1 (-1100 925)(-375 925);
WIRE 16 -1 (-375 825)(-375 725);
WIRE 16 -1 (-1100 825)(-375 825);
WIRE 16 -1 (-375 625)(-375 725);
WIRE 16 -1 (-1100 725)(-375 725);
WIRE 16 -1 (-375 525)(-375 625);
WIRE 16 -1 (-1100 625)(-375 625);
WIRE 16 -1 (-1100 525)(-375 525);
WIRE 16 -1 (-1575 525)(-1300 525);
WIRE 16 -1 (-1575 625)(-1575 525);
WIRE 16 -1 (-1575 625)(-1300 625);
WIRE 16 -1 (-1575 725)(-1575 625);
WIRE 16 -1 (-1575 725)(-1300 725);
WIRE 16 -1 (-1575 825)(-1575 725);
WIRE 16 -1 (-1575 825)(-1300 825);
WIRE 16 -1 (-1575 925)(-1575 825);
WIRE 16 -1 (-1575 1025)(-1575 925);
WIRE 16 -1 (-1575 925)(-1300 925);
WIRE 16 -1 (-1575 1025)(-1300 1025);
WIRE 16 -1 (-1575 1125)(-1575 1025);
WIRE 16 -1 (-1575 1125)(-1300 1125);
WIRE 16 -1 (-1575 1225)(-1575 1125);
WIRE 16 -1 (-1575 1225)(-1300 1225);
WIRE 16 -1 (-1575 1325)(-1575 1225);
WIRE 16 -1 (-1575 1325)(-1300 1325);
WIRE 16 -1 (-1575 1425)(-1575 1325);
WIRE 16 -1 (-1575 1425)(-1300 1425);
WIRE 16 -1 (-1575 1525)(-1575 1425);
WIRE 16 -1 (-1575 1525)(-1300 1525);
WIRE 16 -1 (-1575 1625)(-1575 1525);
WIRE 16 -1 (-1575 1625)(-1300 1625);
WIRE 16 -1 (-1575 1725)(-1575 1625);
WIRE 16 -1 (-1575 1725)(-1300 1725);
WIRE 16 -1 (-1575 1825)(-1575 1725);
WIRE 16 -1 (-1575 2100)(-1575 1825);
WIRE 16 -1 (-1575 1825)(-1300 1825);
WIRE 16 -1 (-5250 5075)(-4650 5075);
WIRE 16 -1 (-4650 5075)(-4650 5025);
WIRE 16 -1 (-4650 5025)(-4650 4925);
WIRE 16 -1 (-5250 5025)(-4650 5025);
WIRE 16 -1 (-5250 4925)(-4650 4925);
WIRE 16 -1 (-4650 4925)(-4650 4825);
WIRE 16 -1 (-6975 3000)(-6800 3000);
WIRE 16 -1 (-6800 3075)(-6800 3000);
WIRE 16 -1 (-6800 3125)(-6800 3075);
WIRE 16 -1 (-6975 3075)(-6800 3075);
WIRE 16 -1 (-6800 3275)(-6800 3125);
WIRE 16 -1 (-6975 3125)(-6800 3125);
WIRE 16 -1 (-6825 6325)(-6825 5750);
WIRE 16 -1 (-6825 5750)(-6950 5750);
WIRE 16 -1 (-4650 5400)(-4650 5350);
WIRE 16 -1 (-4650 5500)(-4650 5400);
WIRE 16 -1 (-4650 5400)(-4825 5400);
WIRE 16 -1 (-4650 5350)(-4650 5275);
WIRE 16 -1 (-4650 5350)(-4825 5350);
WIRE 16 -1 (-4650 5275)(-4825 5275);
WIRE 16 -1 (-4650 5975)(-4650 5900);
WIRE 16 -1 (-4650 5900)(-4825 5900);
WIRE 16 -1 (-4650 5900)(-4650 5850);
WIRE 16 -1 (-4650 5850)(-4825 5850);
WIRE 16 -1 (-3350 1975)(-2100 1975);
WIRE 16 -1 (-2100 1975)(-2100 1875);
WIRE 16 -1 (-2100 1875)(-2100 1775);
WIRE 16 -1 (-3350 1875)(-2100 1875);
WIRE 16 -1 (-2100 1775)(-2100 1675);
WIRE 16 -1 (-3350 1775)(-2100 1775);
WIRE 16 -1 (-2100 1675)(-2100 1575);
WIRE 16 -1 (-3350 1675)(-2100 1675);
WIRE 16 -1 (-2100 1375)(-2100 1575);
WIRE 16 -1 (-3350 1575)(-2100 1575);
WIRE 16 -1 (-2100 1275)(-2100 1375);
WIRE 16 -1 (-3350 1375)(-2100 1375);
WIRE 16 -1 (-2100 1175)(-2100 1275);
WIRE 16 -1 (-3350 1275)(-2100 1275);
WIRE 16 -1 (-2100 1175)(-2100 1075);
WIRE 16 -1 (-3350 1175)(-2100 1175);
WIRE 16 -1 (-2100 725)(-2100 1075);
WIRE 16 -1 (-3350 1075)(-2100 1075);
WIRE 16 -1 (-3825 1075)(-3550 1075);
WIRE 16 -1 (-3825 1175)(-3825 1075);
WIRE 16 -1 (-3825 1175)(-3550 1175);
WIRE 16 -1 (-3825 1275)(-3825 1175);
WIRE 16 -1 (-3825 1275)(-3550 1275);
WIRE 16 -1 (-3825 1375)(-3825 1275);
WIRE 16 -1 (-3825 1375)(-3550 1375);
WIRE 16 -1 (-3825 1575)(-3825 1375);
WIRE 16 -1 (-3825 1575)(-3550 1575);
WIRE 16 -1 (-3825 1675)(-3825 1575);
WIRE 16 -1 (-3825 1675)(-3550 1675);
WIRE 16 -1 (-3825 1775)(-3825 1675);
WIRE 16 -1 (-3825 1775)(-3550 1775);
WIRE 16 -1 (-3825 1875)(-3825 1775);
WIRE 16 -1 (-3825 1875)(-3550 1875);
WIRE 16 -1 (-3825 1975)(-3825 1875);
WIRE 16 -1 (-3825 2100)(-3825 1975);
WIRE 16 -1 (-3825 1975)(-3550 1975);
WIRE 16 -1 (-1450 5200)(-3625 5200);
FORCEPROP 2 LAST SIG_NAME RST_PERST_E1S_0_N
J 0
(-2050 5210);
DISPLAY 0.489362 (-2050 5210);
WIRE 16 -1 (-3625 5200)(-3625 4575);
WIRE 16 -1 (-3425 4575)(-3425 5125);
WIRE 16 -1 (-1450 5125)(-3425 5125);
FORCEPROP 2 LAST SIG_NAME RST_PERST_M2_0_N
J 0
(-2050 5135);
DISPLAY 0.489362 (-2050 5135);
WIRE 16 -1 (-7150 3600)(-8175 3600);
FORCEPROP 2 LAST SIG_NAME P12V_OCP_SFF_EN_R
J 0
(-8075 3610);
DISPLAY 0.489362 (-8075 3610);
WIRE 16 -1 (-3300 3350)(-3300 3575);
WIRE 16 -1 (-2275 3575)(-3300 3575);
FORCEPROP 2 LAST SIG_NAME FM_I3C_CPU1_MUX0_OE_N
J 0
(-2960 3585);
DISPLAY 0.489362 (-2960 3585);
WIRE 16 -1 (-7150 5475)(-8150 5475);
FORCEPROP 2 LAST SIG_NAME PVDDCR_CPU0_P1_PMALERT
J 0
(-8050 5485);
DISPLAY 0.489362 (-8050 5485);
WIRE 16 -1 (-7150 5575)(-8150 5575);
FORCEPROP 2 LAST SIG_NAME PVDDCR_CPU0_P0_PMALERT
J 0
(-8050 5585);
DISPLAY 0.489362 (-8050 5585);
WIRE 16 -1 (-8150 5425)(-7150 5425);
FORCEPROP 2 LAST SIG_NAME PVDDCR_CPU1_P1_SMB_ALERT
J 0
(-8050 5435);
DISPLAY 0.489362 (-8050 5435);
WIRE 16 -1 (-8150 5525)(-7150 5525);
FORCEPROP 2 LAST SIG_NAME PVDDCR_CPU1_P0_SMB_ALERT
J 0
(-8050 5535);
DISPLAY 0.489362 (-8050 5535);
WIRE 16 -1 (-7150 5325)(-8150 5325);
FORCEPROP 2 LAST SIG_NAME PVDD11_S3_P1_PMALERT
J 0
(-8050 5335);
DISPLAY 0.489362 (-8050 5335);
WIRE 16 -1 (-7150 5375)(-8150 5375);
FORCEPROP 2 LAST SIG_NAME PVDD11_S3_P0_PMALERT
J 0
(-8050 5385);
DISPLAY 0.489362 (-8050 5385);
WIRE 16 -1 (-8150 5250)(-7150 5250);
FORCEPROP 2 LAST SIG_NAME PRSNT_HDT_N
J 0
(-8050 5260);
DISPLAY 0.489362 (-8050 5260);
WIRE 16 -1 (-8175 4325)(-7150 4325);
FORCEPROP 0 LAST CDS_PHYS_NET_NAME FM_SYS_THROTTLE_N
J 0
(-8150 4367);
PAINT MONO (-8150 4367);
DISPLAY INVISIBLE (-8150 4367);
FORCEPROP 0 LAST SIG_NAME FM_SYS_THROTTLE_N
J 0
(-8050 4335);
DISPLAY 0.489362 (-8050 4335);
WIRE 16 -1 (-7175 3125)(-8175 3125);
FORCEPROP 2 LAST SIG_NAME CPLD_JTAG_EN
J 0
(-8050 3135);
DISPLAY 0.489362 (-8050 3135);
WIRE 16 -1 (-7175 3075)(-8175 3075);
FORCEPROP 2 LAST SIG_NAME CPLD_PROGRAMN
J 0
(-8050 3085);
DISPLAY 0.489362 (-8050 3085);
WIRE 16 -1 (-8175 4200)(-7150 4200);
FORCEPROP 2 LAST SIG_NAME E1S_0_P12V_EN
J 0
(-8050 4210);
DISPLAY 0.489362 (-8050 4210);
WIRE 16 -1 (-8150 5125)(-7150 5125);
FORCEPROP 2 LAST SIG_NAME FM_SEC_MUX_SEL
J 0
(-8060 5135);
DISPLAY 0.680851 (-8060 5135);
WIRE 16 -1 (-8150 4925)(-7150 4925);
FORCEPROP 2 LAST SIG_NAME FM_APML_MUX2_OE_N
J 0
(-8085 4935);
DISPLAY 0.680851 (-8085 4935);
WIRE 16 -1 (-8175 3825)(-7150 3825);
FORCEPROP 2 LAST SIG_NAME P12V_OCP_V3_2_EN_R
J 0
(-8075 3835);
DISPLAY 0.489362 (-8075 3835);
WIRE 16 -1 (-7150 3775)(-8175 3775);
FORCEPROP 2 LAST SIG_NAME P3V3_OCP_V3_2_EN_R
J 0
(-8075 3785);
DISPLAY 0.489362 (-8075 3785);
WIRE 16 -1 (-8150 5175)(-7150 5175);
FORCEPROP 2 LAST SIG_NAME FM_SEC_MUX_OE_N
J 0
(-8060 5185);
DISPLAY 0.680851 (-8060 5185);
WIRE 16 -1 (-7150 5750)(-8150 5750);
FORCEPROP 2 LAST SIG_NAME SCM_USB_OC_N
J 0
(-8050 5760);
DISPLAY 0.489362 (-8050 5760);
WIRE 16 -1 (-6075 5900)(-5025 5900);
FORCEPROP 2 LAST SIG_NAME FM_P1_PCC0_N
J 0
(-5850 5910);
DISPLAY 0.489362 (-5850 5910);
WIRE 16 -1 (-6075 5850)(-5025 5850);
FORCEPROP 2 LAST SIG_NAME FM_P1_PCC1_N
J 0
(-5850 5860);
DISPLAY 0.489362 (-5850 5860);
WIRE 16 -1 (-8175 3650)(-7150 3650);
FORCEPROP 2 LAST SIG_NAME P3V3_OCP_SFF_EN_R
J 0
(-8075 3660);
DISPLAY 0.489362 (-8075 3660);
WIRE 16 -1 (-7150 3950)(-8175 3950);
FORCEPROP 2 LAST SIG_NAME E1S_0_P3V3_EN
J 0
(-8075 3960);
DISPLAY 0.489362 (-8075 3960);
WIRE 16 -1 (-3300 6175)(-2075 6175);
FORCEPROP 2 LAST SIG_NAME RST_CPU0_PERST1_N
J 0
(-2625 6185);
DISPLAY 0.489362 (-2625 6185);
WIRE 16 -1 (-3300 5900)(-3300 6175);
WIRE 16 -1 (-2875 5900)(-2875 6075);
WIRE 16 -1 (-2075 6075)(-2875 6075);
FORCEPROP 2 LAST SIG_NAME RST_CPU1_PERST1_N
J 0
(-2625 6085);
DISPLAY 0.489362 (-2625 6085);
WIRE 16 -1 (-3100 6125)(-2075 6125);
FORCEPROP 2 LAST SIG_NAME RST_CPU1_PERST0_N
J 0
(-2625 6135);
DISPLAY 0.489362 (-2625 6135);
WIRE 16 -1 (-3100 5900)(-3100 6125);
WIRE 16 -1 (-4050 3800)(-2275 3800);
FORCEPROP 2 LAST SIG_NAME FM_APML_MUX2_SEL
J 0
(-3585 3810);
DISPLAY 0.680851 (-3585 3810);
WIRE 16 -1 (-4050 3800)(-4050 3350);
WIRE 16 -1 (-3500 6225)(-2075 6225);
FORCEPROP 2 LAST SIG_NAME RST_CPU0_PERST0_N
J 0
(-2625 6235);
DISPLAY 0.489362 (-2625 6235);
WIRE 16 -1 (-3500 5900)(-3500 6225);
WIRE 16 -1 (-3075 3525)(-2275 3525);
FORCEPROP 2 LAST SIG_NAME FM_I3C_CPU1_MUX1_OE_N
J 0
(-2960 3535);
DISPLAY 0.489362 (-2960 3535);
WIRE 16 -1 (-3075 3350)(-3075 3525);
WIRE 16 -1 (-3700 3350)(-3700 3675);
WIRE 16 -1 (-2275 3675)(-3700 3675);
FORCEPROP 2 LAST SIG_NAME FM_I3C_CPU0_MUX0_OE_N
J 0
(-2960 3685);
DISPLAY 0.489362 (-2960 3685);
WIRE 16 -1 (-3500 3350)(-3500 3625);
WIRE 16 -1 (-2275 3625)(-3500 3625);
FORCEPROP 2 LAST SIG_NAME FM_I3C_CPU0_MUX1_OE_N
J 0
(-2960 3635);
DISPLAY 0.489362 (-2960 3635);
WIRE 16 -1 (-2875 3450)(-2275 3450);
FORCEPROP 2 LAST SIG_NAME FM_SEC_MUX_OE_N
J 0
(-2810 3460);
DISPLAY 0.680851 (-2810 3460);
WIRE 16 -1 (-2875 3350)(-2875 3450);
WIRE 16 -1 (-2675 3400)(-2275 3400);
FORCEPROP 2 LAST SIG_NAME FM_SEC_MUX_SEL
J 0
(-2685 3410);
DISPLAY 0.680851 (-2685 3410);
WIRE 16 -1 (-2675 3400)(-2675 3325);
WIRE 16 -1 (-5025 5400)(-6050 5400);
FORCEPROP 2 LAST SIG_NAME FM_P0_PCC0_N
J 0
(-5825 5410);
DISPLAY 0.489362 (-5825 5410);
WIRE 16 -1 (-5025 5350)(-6050 5350);
FORCEPROP 2 LAST SIG_NAME FM_P0_PCC1_N
J 0
(-5825 5360);
DISPLAY 0.489362 (-5825 5360);
WIRE 16 -1 (-5025 5275)(-6050 5275);
FORCEPROP 2 LAST SIG_NAME RST_CPU0_KBRST_R_N
J 0
(-5825 5285);
DISPLAY 0.489362 (-5825 5285);
WIRE 16 -1 (-6050 5075)(-5450 5075);
FORCEPROP 2 LAST SIG_NAME RST_PERST_CPU0_SWB_N
J 0
(-6060 5085);
DISPLAY 0.446809 (-6060 5085);
PAINT WHITE (-6060 5085);
WIRE 16 -1 (-6050 5025)(-5450 5025);
FORCEPROP 2 LAST SIG_NAME RST_PERST_CPU1_SWB_N
J 0
(-6060 5035);
DISPLAY 0.446809 (-6060 5035);
PAINT WHITE (-6060 5035);
WIRE 16 -1 (-6050 4925)(-5450 4925);
FORCEPROP 2 LAST SIG_NAME RST_PERST_CPU1_SWB_1_N
J 0
(-6060 4935);
DISPLAY 0.446809 (-6060 4935);
PAINT WHITE (-6060 4935);
WIRE 16 -1 (-2275 3925)(-4475 3925);
FORCEPROP 2 LAST SIG_NAME FM_ESPI_CPU0_ALERT_R_SEL
J 0
(-3810 3935);
DISPLAY 0.680851 (-3810 3935);
WIRE 16 -1 (-4475 3925)(-4475 3375);
WIRE 16 -1 (-4250 3850)(-2275 3850);
FORCEPROP 2 LAST SIG_NAME FM_APML_MUX2_OE_N
J 0
(-3610 3885);
DISPLAY 0.680851 (-3610 3885);
WIRE 16 -1 (-4250 3350)(-4250 3850);
DOT 1 (-6800 4325);
DOT 1 (-4650 4925);
DOT 1 (-6800 3075);
DOT 1 (-6800 3125);
DOT 1 (-6800 3775);
DOT 1 (-6800 3825);
DOT 1 (-6800 3650);
DOT 1 (-6800 5375);
DOT 1 (-6800 5325);
DOT 1 (-6800 5475);
DOT 1 (-6800 5575);
DOT 1 (-6800 5425);
DOT 1 (-6800 5525);
DOT 1 (-4650 5350);
DOT 1 (-4650 5400);
DOT 1 (-4650 5900);
DOT 1 (-3825 1175);
DOT 1 (-3825 1275);
DOT 1 (-3825 1375);
DOT 1 (-3825 1675);
DOT 1 (-3825 1575);
DOT 1 (-3825 1775);
DOT 1 (-3825 1975);
DOT 1 (-3825 1875);
DOT 1 (-2100 1175);
DOT 1 (-2100 1075);
DOT 1 (-2100 1275);
DOT 1 (-2100 1375);
DOT 1 (-2100 1575);
DOT 1 (-2100 1775);
DOT 1 (-2100 1875);
DOT 1 (-1575 625);
DOT 1 (-1575 725);
DOT 1 (-1575 825);
DOT 1 (-1575 925);
DOT 1 (-1575 1025);
DOT 1 (-1575 1225);
DOT 1 (-1575 1125);
DOT 1 (-1575 1325);
DOT 1 (-1575 1425);
DOT 1 (-1575 1525);
DOT 1 (-1575 1725);
DOT 1 (-1575 1625);
DOT 1 (-1575 1825);
DOT 1 (-375 625);
DOT 1 (-375 725);
DOT 1 (-375 825);
DOT 1 (-375 925);
DOT 1 (-375 1025);
DOT 1 (-375 1125);
DOT 1 (-375 1225);
DOT 1 (-375 1325);
DOT 1 (-375 1425);
DOT 1 (-375 1525);
DOT 1 (-375 1725);
DOT 1 (-375 1625);
DOT 1 (-6800 4200);
DOT 1 (-6800 5125);
DOT 1 (-6800 4925);
DOT 1 (-6800 4875);
DOT 1 (-4650 5025);
DOT 1 (-6800 5250);
DOT 1 (-6800 5175);
DOT 1 (-2100 1675);
DOT 1 (-6800 3950);
DOT 1 (-6800 4575);
QUIT
